(kicad_pcb (version 20211014) (generator pcbnew)

  (general
    (thickness 1.6)
  )

  (paper "A4")
  (title_block
    (title "SI test board")
    (rev "1.0.1")
    (company "Antmicro")
  )

  (layers
    (0 "F.Cu" signal)
    (1 "In1.Cu" signal)
    (2 "In2.Cu" signal)
    (31 "B.Cu" signal)
    (32 "B.Adhes" user "B.Adhesive")
    (33 "F.Adhes" user "F.Adhesive")
    (34 "B.Paste" user)
    (35 "F.Paste" user)
    (36 "B.SilkS" user "B.Silkscreen")
    (37 "F.SilkS" user "F.Silkscreen")
    (38 "B.Mask" user)
    (39 "F.Mask" user)
    (40 "Dwgs.User" user "User.Drawings")
    (41 "Cmts.User" user "User.Comments")
    (42 "Eco1.User" user "User.Eco1")
    (43 "Eco2.User" user "User.Eco2")
    (44 "Edge.Cuts" user)
    (45 "Margin" user)
    (46 "B.CrtYd" user "B.Courtyard")
    (47 "F.CrtYd" user "F.Courtyard")
    (48 "B.Fab" user)
    (49 "F.Fab" user)
  )

  (setup
    (stackup
      (layer "F.SilkS" (type "Top Silk Screen"))
      (layer "F.Paste" (type "Top Solder Paste"))
      (layer "F.Mask" (type "Top Solder Mask") (color "Black") (thickness 0.01))
      (layer "F.Cu" (type "copper") (thickness 0.035))
      (layer "dielectric 1" (type "core") (thickness 0.12) (material "FR4") (epsilon_r 4.18) (loss_tangent 0.02))
      (layer "In1.Cu" (type "copper") (thickness 0.035))
      (layer "dielectric 2" (type "prepreg") (thickness 1.2) (material "FR4") (epsilon_r 4.18) (loss_tangent 0.02))
      (layer "In2.Cu" (type "copper") (thickness 0.035))
      (layer "dielectric 3" (type "core") (thickness 0.12) (material "FR4") (epsilon_r 4.18) (loss_tangent 0.02))
      (layer "B.Cu" (type "copper") (thickness 0.035))
      (layer "B.Mask" (type "Bottom Solder Mask") (color "Black") (thickness 0.01))
      (layer "B.Paste" (type "Bottom Solder Paste"))
      (layer "B.SilkS" (type "Bottom Silk Screen"))
      (copper_finish "None")
      (dielectric_constraints no)
    )
    (pad_to_mask_clearance 0)
    (pcbplotparams
      (layerselection 0x00010fc_ffffffff)
      (disableapertmacros false)
      (usegerberextensions false)
      (usegerberattributes true)
      (usegerberadvancedattributes true)
      (creategerberjobfile true)
      (svguseinch false)
      (svgprecision 6)
      (excludeedgelayer true)
      (plotframeref false)
      (viasonmask false)
      (mode 1)
      (useauxorigin false)
      (hpglpennumber 1)
      (hpglpenspeed 20)
      (hpglpendiameter 15.000000)
      (dxfpolygonmode true)
      (dxfimperialunits true)
      (dxfusepcbnewfont true)
      (psnegative false)
      (psa4output false)
      (plotreference true)
      (plotvalue true)
      (plotinvisibletext false)
      (sketchpadsonfab false)
      (subtractmaskfromsilk false)
      (outputformat 1)
      (mirror false)
      (drillshape 1)
      (scaleselection 1)
      (outputdirectory "")
    )
  )

  (net 0 "")
  (net 1 "Net-(J1-Pad1)")
  (net 2 "GND")
  (net 3 "unconnected-(J3-Pad1)")
  (net 4 "Net-(AE1-Pad1)")
  (net 5 "Net-(J7-Pad1)")
  (net 6 "Net-(J10-Pad1)")
  (net 7 "/DIFF_P")
  (net 8 "/DIFF_N")
  (net 9 "Net-(J15-Pad1)")
  (net 10 "Net-(J16-Pad1)")
  (net 11 "Net-(J6-Pad1)")
  (net 12 "unconnected-(J21-Pad1)")
  (net 13 "unconnected-(J22-Pad1)")

  (footprint "si-simulation-test-board-footprints:RF_SMA_BoardEdge_RF2-143-T-17-50-G" (layer "F.Cu")
    (tedit 64FEFFC5)
    (at 146.68 137.6155 -90)
    (descr "RF SMA SMD board edge connector")
    (property "Author" "Antmicro")
    (property "License" "Apache-2.0")
    (property "MPN" "RF2-143-T-17-50-G")
    (property "Manufacturer" "ADAM TECH")
    (property "Sheetfile" "si-simulation-test-board.kicad_sch")
    (property "Sheetname" "")
    (attr smd)
    (fp_text reference "J17" (at -4.5 6.88) (layer "F.SilkS")
      (effects (font (size 0.7 0.7) (thickness 0.15)) (justify left bottom))
    )
    (fp_text value "Conn_SMA_RF2-143-T-17-50-G" (at 0 9.24 -90) (layer "F.Fab")
      (effects (font (size 0.7 0.7) (thickness 0.15)) (justify left bottom))
    )
    (fp_text user "Author: Antmicro" (at -4.5 11.24 -90) (layer "F.Fab") hide
      (effects (font (size 0.7 0.7) (thickness 0.15)) (justify left bottom))
    )
    (fp_text user "License: Apache-2.0" (at -4.5 12.44 -90) (layer "F.Fab") hide
      (effects (font (size 0.7 0.7) (thickness 0.15)) (justify left bottom))
    )
    (fp_text user "${REFERENCE}" (at -4.5 13.64 -90) (layer "F.Fab") hide
      (effects (font (size 0.7 0.7) (thickness 0.15)) (justify left bottom))
    )
    (fp_rect (start -3.995 -7.53) (end 3.995 7.53) (layer "B.CrtYd") (width 0.05) (fill none))
    (fp_rect (start -3.995 -7.53) (end 3.995 7.53) (layer "F.CrtYd") (width 0.05) (fill none))
    (fp_line (start 0.38 2.654) (end 0.375 6.455) (layer "F.Fab") (width 0.15))
    (fp_line (start -3.174 6.455) (end -3.174 1.504) (layer "F.Fab") (width 0.15))
    (fp_line (start 2.65 -6.375) (end 2.65 1.504) (layer "F.Fab") (width 0.15))
    (fp_line (start 0.375 6.455) (end -0.38 6.455) (layer "F.Fab") (width 0.15))
    (fp_line (start -2.375 6.455) (end -3.174 6.455) (layer "F.Fab") (width 0.15))
    (fp_line (start 3.174 6.455) (end 3.174 1.504) (layer "F.Fab") (width 0.15))
    (fp_line (start 2.375 6.455) (end 2.375 2.678) (layer "F.Fab") (width 0.15))
    (fp_line (start -0.38 2.654) (end -0.38 6.455) (layer "F.Fab") (width 0.15))
    (fp_line (start -2.375 2.678) (end -2.375 6.455) (layer "F.Fab") (width 0.15))
    (fp_line (start 3.174 1.504) (end -3.174 1.504) (layer "F.Fab") (width 0.15))
    (fp_line (start 3.174 6.455) (end 2.375 6.455) (layer "F.Fab") (width 0.15))
    (fp_line (start 2.65 -6.375) (end -2.65 -6.375) (layer "F.Fab") (width 0.15))
    (fp_line (start -2.65 -6.375) (end -2.65 1.504) (layer "F.Fab") (width 0.15))
    (fp_line (start 3.174 2.654) (end -3.15 2.654) (layer "F.Fab") (width 0.15))
    (pad "1" smd rect (at 0.007 4.955 270) (size 2.29 4.191) (layers "F.Cu" "F.Paste" "F.Mask")
      (net 9 "Net-(J15-Pad1)") (pinfunction "1") (pintype "passive"))
    (pad "2" smd rect (at 2.975 4.955 270) (size 1.45 4.191) (layers "B.Cu" "B.Paste" "B.Mask")
      (net 2 "GND") (pinfunction "2") (pintype "passive"))
    (pad "2" smd rect (at -2.975 4.955 270) (size 1.45 4.191) (layers "F.Cu" "F.Paste" "F.Mask")
      (net 2 "GND") (pinfunction "2") (pintype "passive"))
    (pad "2" smd rect (at 2.975 4.955 270) (size 1.45 4.191) (layers "F.Cu" "F.Paste" "F.Mask")
      (net 2 "GND") (pinfunction "2") (pintype "passive"))
    (pad "2" smd rect (at -2.975 4.955 270) (size 1.45 4.191) (layers "B.Cu" "B.Paste" "B.Mask")
      (net 2 "GND") (pinfunction "2") (pintype "passive"))
  )

  (footprint "si-simulation-test-board-footprints:RF_SMA_BoardEdge_RF2-143-T-17-50-G" (layer "F.Cu")
    (tedit 64FEFFC5)
    (at 146.68 86.0005 -90)
    (descr "RF SMA SMD board edge connector")
    (property "Author" "Antmicro")
    (property "License" "Apache-2.0")
    (property "MPN" "RF2-143-T-17-50-G")
    (property "Manufacturer" "ADAM TECH")
    (property "Sheetfile" "si-simulation-test-board.kicad_sch")
    (property "Sheetname" "")
    (attr smd)
    (fp_text reference "J8" (at -4.5 6.88) (layer "F.SilkS")
      (effects (font (size 0.7 0.7) (thickness 0.15)) (justify left bottom))
    )
    (fp_text value "Conn_SMA_RF2-143-T-17-50-G" (at 0 9.24 -90) (layer "F.Fab")
      (effects (font (size 0.7 0.7) (thickness 0.15)) (justify left bottom))
    )
    (fp_text user "${REFERENCE}" (at -4.5 13.64 -90) (layer "F.Fab") hide
      (effects (font (size 0.7 0.7) (thickness 0.15)) (justify left bottom))
    )
    (fp_text user "License: Apache-2.0" (at -4.5 12.44 -90) (layer "F.Fab") hide
      (effects (font (size 0.7 0.7) (thickness 0.15)) (justify left bottom))
    )
    (fp_text user "Author: Antmicro" (at -4.5 11.24 -90) (layer "F.Fab") hide
      (effects (font (size 0.7 0.7) (thickness 0.15)) (justify left bottom))
    )
    (fp_rect (start -3.995 -7.53) (end 3.995 7.53) (layer "B.CrtYd") (width 0.05) (fill none))
    (fp_rect (start -3.995 -7.53) (end 3.995 7.53) (layer "F.CrtYd") (width 0.05) (fill none))
    (fp_line (start -0.38 2.654) (end -0.38 6.455) (layer "F.Fab") (width 0.15))
    (fp_line (start 3.174 6.455) (end 2.375 6.455) (layer "F.Fab") (width 0.15))
    (fp_line (start 2.65 -6.375) (end 2.65 1.504) (layer "F.Fab") (width 0.15))
    (fp_line (start -2.375 2.678) (end -2.375 6.455) (layer "F.Fab") (width 0.15))
    (fp_line (start 3.174 6.455) (end 3.174 1.504) (layer "F.Fab") (width 0.15))
    (fp_line (start 2.375 6.455) (end 2.375 2.678) (layer "F.Fab") (width 0.15))
    (fp_line (start -3.174 6.455) (end -3.174 1.504) (layer "F.Fab") (width 0.15))
    (fp_line (start 0.375 6.455) (end -0.38 6.455) (layer "F.Fab") (width 0.15))
    (fp_line (start -2.65 -6.375) (end -2.65 1.504) (layer "F.Fab") (width 0.15))
    (fp_line (start 2.65 -6.375) (end -2.65 -6.375) (layer "F.Fab") (width 0.15))
    (fp_line (start 3.174 2.654) (end -3.15 2.654) (layer "F.Fab") (width 0.15))
    (fp_line (start -2.375 6.455) (end -3.174 6.455) (layer "F.Fab") (width 0.15))
    (fp_line (start 0.38 2.654) (end 0.375 6.455) (layer "F.Fab") (width 0.15))
    (fp_line (start 3.174 1.504) (end -3.174 1.504) (layer "F.Fab") (width 0.15))
    (pad "1" smd rect (at 0.007 4.955 270) (size 2.29 4.191) (layers "F.Cu" "F.Paste" "F.Mask")
      (net 5 "Net-(J7-Pad1)") (pinfunction "1") (pintype "passive"))
    (pad "2" smd rect (at 2.975 4.955 270) (size 1.45 4.191) (layers "B.Cu" "B.Paste" "B.Mask")
      (net 2 "GND") (pinfunction "2") (pintype "passive"))
    (pad "2" smd rect (at -2.975 4.955 270) (size 1.45 4.191) (layers "B.Cu" "B.Paste" "B.Mask")
      (net 2 "GND") (pinfunction "2") (pintype "passive"))
    (pad "2" smd rect (at -2.975 4.955 270) (size 1.45 4.191) (layers "F.Cu" "F.Paste" "F.Mask")
      (net 2 "GND") (pinfunction "2") (pintype "passive"))
    (pad "2" smd rect (at 2.975 4.955 270) (size 1.45 4.191) (layers "F.Cu" "F.Paste" "F.Mask")
      (net 2 "GND") (pinfunction "2") (pintype "passive"))
  )

  (footprint "si-simulation-test-board-footprints:RF_SMA_BoardEdge_RF2-143-T-17-50-G" (layer "F.Cu")
    (tedit 64FEFFC5)
    (at 146.78 127.6155 -90)
    (descr "RF SMA SMD board edge connector")
    (property "Author" "Antmicro")
    (property "License" "Apache-2.0")
    (property "MPN" "RF2-143-T-17-50-G")
    (property "Manufacturer" "ADAM TECH")
    (property "Sheetfile" "si-simulation-test-board.kicad_sch")
    (property "Sheetname" "")
    (attr smd)
    (fp_text reference "J20" (at -4.5 6.88) (layer "F.SilkS")
      (effects (font (size 0.7 0.7) (thickness 0.15)) (justify left bottom))
    )
    (fp_text value "Conn_SMA_RF2-143-T-17-50-G" (at 0 9.24 -90) (layer "F.Fab")
      (effects (font (size 0.7 0.7) (thickness 0.15)) (justify left bottom))
    )
    (fp_text user "${REFERENCE}" (at -4.5 13.64 -90) (layer "F.Fab") hide
      (effects (font (size 0.7 0.7) (thickness 0.15)) (justify left bottom))
    )
    (fp_text user "Author: Antmicro" (at -4.5 11.24 -90) (layer "F.Fab") hide
      (effects (font (size 0.7 0.7) (thickness 0.15)) (justify left bottom))
    )
    (fp_text user "License: Apache-2.0" (at -4.5 12.44 -90) (layer "F.Fab") hide
      (effects (font (size 0.7 0.7) (thickness 0.15)) (justify left bottom))
    )
    (fp_rect (start -3.995 -7.53) (end 3.995 7.53) (layer "B.CrtYd") (width 0.05) (fill none))
    (fp_rect (start -3.995 -7.53) (end 3.995 7.53) (layer "F.CrtYd") (width 0.05) (fill none))
    (fp_line (start 3.174 6.455) (end 2.375 6.455) (layer "F.Fab") (width 0.15))
    (fp_line (start -3.174 6.455) (end -3.174 1.504) (layer "F.Fab") (width 0.15))
    (fp_line (start 0.375 6.455) (end -0.38 6.455) (layer "F.Fab") (width 0.15))
    (fp_line (start -2.65 -6.375) (end -2.65 1.504) (layer "F.Fab") (width 0.15))
    (fp_line (start -0.38 2.654) (end -0.38 6.455) (layer "F.Fab") (width 0.15))
    (fp_line (start 3.174 1.504) (end -3.174 1.504) (layer "F.Fab") (width 0.15))
    (fp_line (start -2.375 2.678) (end -2.375 6.455) (layer "F.Fab") (width 0.15))
    (fp_line (start 0.38 2.654) (end 0.375 6.455) (layer "F.Fab") (width 0.15))
    (fp_line (start 2.375 6.455) (end 2.375 2.678) (layer "F.Fab") (width 0.15))
    (fp_line (start -2.375 6.455) (end -3.174 6.455) (layer "F.Fab") (width 0.15))
    (fp_line (start 3.174 2.654) (end -3.15 2.654) (layer "F.Fab") (width 0.15))
    (fp_line (start 3.174 6.455) (end 3.174 1.504) (layer "F.Fab") (width 0.15))
    (fp_line (start 2.65 -6.375) (end -2.65 -6.375) (layer "F.Fab") (width 0.15))
    (fp_line (start 2.65 -6.375) (end 2.65 1.504) (layer "F.Fab") (width 0.15))
    (pad "1" smd rect (at 0.007 4.955 270) (size 2.29 4.191) (layers "F.Cu" "F.Paste" "F.Mask")
      (net 2 "GND") (pinfunction "1") (pintype "passive"))
    (pad "2" smd rect (at -2.975 4.955 270) (size 1.45 4.191) (layers "F.Cu" "F.Paste" "F.Mask")
      (net 2 "GND") (pinfunction "2") (pintype "passive"))
    (pad "2" smd rect (at 2.975 4.955 270) (size 1.45 4.191) (layers "F.Cu" "F.Paste" "F.Mask")
      (net 2 "GND") (pinfunction "2") (pintype "passive"))
    (pad "2" smd rect (at -2.975 4.955 270) (size 1.45 4.191) (layers "B.Cu" "B.Paste" "B.Mask")
      (net 2 "GND") (pinfunction "2") (pintype "passive"))
    (pad "2" smd rect (at 2.975 4.955 270) (size 1.45 4.191) (layers "B.Cu" "B.Paste" "B.Mask")
      (net 2 "GND") (pinfunction "2") (pintype "passive"))
  )

  (footprint "si-simulation-test-board-footprints:RF_SMA_BoardEdge_RF2-143-T-17-50-G" (layer "F.Cu")
    (tedit 64FEFFC5)
    (at 146.68 117.3005 -90)
    (descr "RF SMA SMD board edge connector")
    (property "Author" "Antmicro")
    (property "License" "Apache-2.0")
    (property "MPN" "RF2-143-T-17-50-G")
    (property "Manufacturer" "ADAM TECH")
    (property "Sheetfile" "si-simulation-test-board.kicad_sch")
    (property "Sheetname" "")
    (attr smd)
    (fp_text reference "J14" (at -4.5 6.88) (layer "F.SilkS")
      (effects (font (size 0.7 0.7) (thickness 0.15)) (justify left bottom))
    )
    (fp_text value "Conn_SMA_RF2-143-T-17-50-G" (at 0 9.24 -90) (layer "F.Fab")
      (effects (font (size 0.7 0.7) (thickness 0.15)) (justify left bottom))
    )
    (fp_text user "License: Apache-2.0" (at -4.5 12.44 -90) (layer "F.Fab") hide
      (effects (font (size 0.7 0.7) (thickness 0.15)) (justify left bottom))
    )
    (fp_text user "${REFERENCE}" (at -4.5 13.64 -90) (layer "F.Fab") hide
      (effects (font (size 0.7 0.7) (thickness 0.15)) (justify left bottom))
    )
    (fp_text user "Author: Antmicro" (at -4.5 11.24 -90) (layer "F.Fab") hide
      (effects (font (size 0.7 0.7) (thickness 0.15)) (justify left bottom))
    )
    (fp_rect (start -3.995 -7.53) (end 3.995 7.53) (layer "B.CrtYd") (width 0.05) (fill none))
    (fp_rect (start -3.995 -7.53) (end 3.995 7.53) (layer "F.CrtYd") (width 0.05) (fill none))
    (fp_line (start 2.65 -6.375) (end -2.65 -6.375) (layer "F.Fab") (width 0.15))
    (fp_line (start -2.375 6.455) (end -3.174 6.455) (layer "F.Fab") (width 0.15))
    (fp_line (start 2.375 6.455) (end 2.375 2.678) (layer "F.Fab") (width 0.15))
    (fp_line (start 2.65 -6.375) (end 2.65 1.504) (layer "F.Fab") (width 0.15))
    (fp_line (start -0.38 2.654) (end -0.38 6.455) (layer "F.Fab") (width 0.15))
    (fp_line (start 3.174 6.455) (end 2.375 6.455) (layer "F.Fab") (width 0.15))
    (fp_line (start 3.174 2.654) (end -3.15 2.654) (layer "F.Fab") (width 0.15))
    (fp_line (start 0.375 6.455) (end -0.38 6.455) (layer "F.Fab") (width 0.15))
    (fp_line (start 3.174 6.455) (end 3.174 1.504) (layer "F.Fab") (width 0.15))
    (fp_line (start 3.174 1.504) (end -3.174 1.504) (layer "F.Fab") (width 0.15))
    (fp_line (start -2.375 2.678) (end -2.375 6.455) (layer "F.Fab") (width 0.15))
    (fp_line (start 0.38 2.654) (end 0.375 6.455) (layer "F.Fab") (width 0.15))
    (fp_line (start -2.65 -6.375) (end -2.65 1.504) (layer "F.Fab") (width 0.15))
    (fp_line (start -3.174 6.455) (end -3.174 1.504) (layer "F.Fab") (width 0.15))
    (pad "1" smd rect (at 0.007 4.955 270) (size 2.29 4.191) (layers "F.Cu" "F.Paste" "F.Mask")
      (net 8 "/DIFF_N") (pinfunction "1") (pintype "passive"))
    (pad "2" smd rect (at -2.975 4.955 270) (size 1.45 4.191) (layers "B.Cu" "B.Paste" "B.Mask")
      (net 2 "GND") (pinfunction "2") (pintype "passive"))
    (pad "2" smd rect (at -2.975 4.955 270) (size 1.45 4.191) (layers "F.Cu" "F.Paste" "F.Mask")
      (net 2 "GND") (pinfunction "2") (pintype "passive"))
    (pad "2" smd rect (at 2.975 4.955 270) (size 1.45 4.191) (layers "B.Cu" "B.Paste" "B.Mask")
      (net 2 "GND") (pinfunction "2") (pintype "passive"))
    (pad "2" smd rect (at 2.975 4.955 270) (size 1.45 4.191) (layers "F.Cu" "F.Paste" "F.Mask")
      (net 2 "GND") (pinfunction "2") (pintype "passive"))
  )

  (footprint "si-simulation-test-board-footprints:RF_SMA_BoardEdge_RF2-143-T-17-50-G" (layer "F.Cu")
    (tedit 64FEFFC5)
    (at 91.37 95.999499 90)
    (descr "RF SMA SMD board edge connector")
    (property "Author" "Antmicro")
    (property "License" "Apache-2.0")
    (property "MPN" "RF2-143-T-17-50-G")
    (property "Manufacturer" "ADAM TECH")
    (property "Sheetfile" "si-simulation-test-board.kicad_sch")
    (property "Sheetname" "")
    (attr smd)
    (fp_text reference "J9" (at -4.5 6.88 180) (layer "F.SilkS")
      (effects (font (size 0.7 0.7) (thickness 0.15)) (justify left bottom))
    )
    (fp_text value "Conn_SMA_RF2-143-T-17-50-G" (at 0 9.24 90) (layer "F.Fab")
      (effects (font (size 0.7 0.7) (thickness 0.15)) (justify left bottom))
    )
    (fp_text user "License: Apache-2.0" (at -4.5 12.44 90) (layer "F.Fab") hide
      (effects (font (size 0.7 0.7) (thickness 0.15)) (justify left bottom))
    )
    (fp_text user "Author: Antmicro" (at -4.5 11.24 90) (layer "F.Fab") hide
      (effects (font (size 0.7 0.7) (thickness 0.15)) (justify left bottom))
    )
    (fp_text user "${REFERENCE}" (at -4.5 13.64 90) (layer "F.Fab") hide
      (effects (font (size 0.7 0.7) (thickness 0.15)) (justify left bottom))
    )
    (fp_rect (start -3.995 -7.53) (end 3.995 7.53) (layer "B.CrtYd") (width 0.05) (fill none))
    (fp_rect (start -3.995 -7.53) (end 3.995 7.53) (layer "F.CrtYd") (width 0.05) (fill none))
    (fp_line (start 0.375 6.455) (end -0.38 6.455) (layer "F.Fab") (width 0.15))
    (fp_line (start 2.65 -6.375) (end 2.65 1.504) (layer "F.Fab") (width 0.15))
    (fp_line (start -2.65 -6.375) (end -2.65 1.504) (layer "F.Fab") (width 0.15))
    (fp_line (start -3.174 6.455) (end -3.174 1.504) (layer "F.Fab") (width 0.15))
    (fp_line (start 2.375 6.455) (end 2.375 2.678) (layer "F.Fab") (width 0.15))
    (fp_line (start -0.38 2.654) (end -0.38 6.455) (layer "F.Fab") (width 0.15))
    (fp_line (start 3.174 1.504) (end -3.174 1.504) (layer "F.Fab") (width 0.15))
    (fp_line (start 3.174 6.455) (end 3.174 1.504) (layer "F.Fab") (width 0.15))
    (fp_line (start -2.375 2.678) (end -2.375 6.455) (layer "F.Fab") (width 0.15))
    (fp_line (start 3.174 6.455) (end 2.375 6.455) (layer "F.Fab") (width 0.15))
    (fp_line (start 2.65 -6.375) (end -2.65 -6.375) (layer "F.Fab") (width 0.15))
    (fp_line (start 3.174 2.654) (end -3.15 2.654) (layer "F.Fab") (width 0.15))
    (fp_line (start -2.375 6.455) (end -3.174 6.455) (layer "F.Fab") (width 0.15))
    (fp_line (start 0.38 2.654) (end 0.375 6.455) (layer "F.Fab") (width 0.15))
    (pad "1" smd rect (at 0.007 4.955 90) (size 2.29 4.191) (layers "F.Cu" "F.Paste" "F.Mask")
      (net 6 "Net-(J10-Pad1)") (pinfunction "1") (pintype "passive"))
    (pad "2" smd rect (at -2.975 4.955 90) (size 1.45 4.191) (layers "B.Cu" "B.Paste" "B.Mask")
      (net 2 "GND") (pinfunction "2") (pintype "passive"))
    (pad "2" smd rect (at 2.975 4.955 90) (size 1.45 4.191) (layers "B.Cu" "B.Paste" "B.Mask")
      (net 2 "GND") (pinfunction "2") (pintype "passive"))
    (pad "2" smd rect (at -2.975 4.955 90) (size 1.45 4.191) (layers "F.Cu" "F.Paste" "F.Mask")
      (net 2 "GND") (pinfunction "2") (pintype "passive"))
    (pad "2" smd rect (at 2.975 4.955 90) (size 1.45 4.191) (layers "F.Cu" "F.Paste" "F.Mask")
      (net 2 "GND") (pinfunction "2") (pintype "passive"))
  )

  (footprint "si-simulation-test-board-footprints:RF_SMA_BoardEdge_RF2-143-T-17-50-G" (layer "F.Cu")
    (tedit 64FEFFC5)
    (at 146.63 66.0005 -90)
    (descr "RF SMA SMD board edge connector")
    (property "Author" "Antmicro")
    (property "License" "Apache-2.0")
    (property "MPN" "RF2-143-T-17-50-G")
    (property "Manufacturer" "ADAM TECH")
    (property "Sheetfile" "si-simulation-test-board.kicad_sch")
    (property "Sheetname" "")
    (attr smd)
    (fp_text reference "J3" (at -4.5 6.88) (layer "F.SilkS")
      (effects (font (size 0.7 0.7) (thickness 0.15)) (justify left bottom))
    )
    (fp_text value "Conn_SMA_RF2-143-T-17-50-G" (at 0 9.24 -90) (layer "F.Fab")
      (effects (font (size 0.7 0.7) (thickness 0.15)) (justify left bottom))
    )
    (fp_text user "License: Apache-2.0" (at -4.5 12.44 -90) (layer "F.Fab") hide
      (effects (font (size 0.7 0.7) (thickness 0.15)) (justify left bottom))
    )
    (fp_text user "Author: Antmicro" (at -4.5 11.24 -90) (layer "F.Fab") hide
      (effects (font (size 0.7 0.7) (thickness 0.15)) (justify left bottom))
    )
    (fp_text user "${REFERENCE}" (at -4.5 13.64 -90) (layer "F.Fab") hide
      (effects (font (size 0.7 0.7) (thickness 0.15)) (justify left bottom))
    )
    (fp_rect (start -3.995 -7.53) (end 3.995 7.53) (layer "B.CrtYd") (width 0.05) (fill none))
    (fp_rect (start -3.995 -7.53) (end 3.995 7.53) (layer "F.CrtYd") (width 0.05) (fill none))
    (fp_line (start 0.38 2.654) (end 0.375 6.455) (layer "F.Fab") (width 0.15))
    (fp_line (start 3.174 2.654) (end -3.15 2.654) (layer "F.Fab") (width 0.15))
    (fp_line (start -2.375 2.678) (end -2.375 6.455) (layer "F.Fab") (width 0.15))
    (fp_line (start -3.174 6.455) (end -3.174 1.504) (layer "F.Fab") (width 0.15))
    (fp_line (start 3.174 6.455) (end 3.174 1.504) (layer "F.Fab") (width 0.15))
    (fp_line (start 2.65 -6.375) (end -2.65 -6.375) (layer "F.Fab") (width 0.15))
    (fp_line (start 2.375 6.455) (end 2.375 2.678) (layer "F.Fab") (width 0.15))
    (fp_line (start 2.65 -6.375) (end 2.65 1.504) (layer "F.Fab") (width 0.15))
    (fp_line (start -0.38 2.654) (end -0.38 6.455) (layer "F.Fab") (width 0.15))
    (fp_line (start 0.375 6.455) (end -0.38 6.455) (layer "F.Fab") (width 0.15))
    (fp_line (start -2.65 -6.375) (end -2.65 1.504) (layer "F.Fab") (width 0.15))
    (fp_line (start -2.375 6.455) (end -3.174 6.455) (layer "F.Fab") (width 0.15))
    (fp_line (start 3.174 6.455) (end 2.375 6.455) (layer "F.Fab") (width 0.15))
    (fp_line (start 3.174 1.504) (end -3.174 1.504) (layer "F.Fab") (width 0.15))
    (pad "1" smd rect (at 0.007 4.955 270) (size 2.29 4.191) (layers "F.Cu" "F.Paste" "F.Mask")
      (net 3 "unconnected-(J3-Pad1)") (pinfunction "1") (pintype "passive+no_connect"))
    (pad "2" smd rect (at 2.975 4.955 270) (size 1.45 4.191) (layers "B.Cu" "B.Paste" "B.Mask")
      (net 2 "GND") (pinfunction "2") (pintype "passive"))
    (pad "2" smd rect (at 2.975 4.955 270) (size 1.45 4.191) (layers "F.Cu" "F.Paste" "F.Mask")
      (net 2 "GND") (pinfunction "2") (pintype "passive"))
    (pad "2" smd rect (at -2.975 4.955 270) (size 1.45 4.191) (layers "F.Cu" "F.Paste" "F.Mask")
      (net 2 "GND") (pinfunction "2") (pintype "passive"))
    (pad "2" smd rect (at -2.975 4.955 270) (size 1.45 4.191) (layers "B.Cu" "B.Paste" "B.Mask")
      (net 2 "GND") (pinfunction "2") (pintype "passive"))
  )

  (footprint "si-simulation-test-board-footprints:RF_SMA_BoardEdge_RF2-143-T-17-50-G" (layer "F.Cu")
    (tedit 64FEFFC5)
    (at 146.68 147.6155 -90)
    (descr "RF SMA SMD board edge connector")
    (property "Author" "Antmicro")
    (property "License" "Apache-2.0")
    (property "MPN" "RF2-143-T-17-50-G")
    (property "Manufacturer" "ADAM TECH")
    (property "Sheetfile" "si-simulation-test-board.kicad_sch")
    (property "Sheetname" "")
    (attr smd)
    (fp_text reference "J18" (at -4.5 6.88) (layer "F.SilkS")
      (effects (font (size 0.7 0.7) (thickness 0.15)) (justify left bottom))
    )
    (fp_text value "Conn_SMA_RF2-143-T-17-50-G" (at 0 9.24 -90) (layer "F.Fab")
      (effects (font (size 0.7 0.7) (thickness 0.15)) (justify left bottom))
    )
    (fp_text user "${REFERENCE}" (at -4.5 13.64 -90) (layer "F.Fab") hide
      (effects (font (size 0.7 0.7) (thickness 0.15)) (justify left bottom))
    )
    (fp_text user "License: Apache-2.0" (at -4.5 12.44 -90) (layer "F.Fab") hide
      (effects (font (size 0.7 0.7) (thickness 0.15)) (justify left bottom))
    )
    (fp_text user "Author: Antmicro" (at -4.5 11.24 -90) (layer "F.Fab") hide
      (effects (font (size 0.7 0.7) (thickness 0.15)) (justify left bottom))
    )
    (fp_rect (start -3.995 -7.53) (end 3.995 7.53) (layer "B.CrtYd") (width 0.05) (fill none))
    (fp_rect (start -3.995 -7.53) (end 3.995 7.53) (layer "F.CrtYd") (width 0.05) (fill none))
    (fp_line (start 0.375 6.455) (end -0.38 6.455) (layer "F.Fab") (width 0.15))
    (fp_line (start 3.174 6.455) (end 3.174 1.504) (layer "F.Fab") (width 0.15))
    (fp_line (start -0.38 2.654) (end -0.38 6.455) (layer "F.Fab") (width 0.15))
    (fp_line (start 3.174 6.455) (end 2.375 6.455) (layer "F.Fab") (width 0.15))
    (fp_line (start 2.65 -6.375) (end -2.65 -6.375) (layer "F.Fab") (width 0.15))
    (fp_line (start -2.65 -6.375) (end -2.65 1.504) (layer "F.Fab") (width 0.15))
    (fp_line (start 2.65 -6.375) (end 2.65 1.504) (layer "F.Fab") (width 0.15))
    (fp_line (start 3.174 2.654) (end -3.15 2.654) (layer "F.Fab") (width 0.15))
    (fp_line (start -3.174 6.455) (end -3.174 1.504) (layer "F.Fab") (width 0.15))
    (fp_line (start 0.38 2.654) (end 0.375 6.455) (layer "F.Fab") (width 0.15))
    (fp_line (start -2.375 6.455) (end -3.174 6.455) (layer "F.Fab") (width 0.15))
    (fp_line (start 3.174 1.504) (end -3.174 1.504) (layer "F.Fab") (width 0.15))
    (fp_line (start 2.375 6.455) (end 2.375 2.678) (layer "F.Fab") (width 0.15))
    (fp_line (start -2.375 2.678) (end -2.375 6.455) (layer "F.Fab") (width 0.15))
    (pad "1" smd rect (at 0.007 4.955 270) (size 2.29 4.191) (layers "F.Cu" "F.Paste" "F.Mask")
      (net 10 "Net-(J16-Pad1)") (pinfunction "1") (pintype "passive"))
    (pad "2" smd rect (at 2.975 4.955 270) (size 1.45 4.191) (layers "B.Cu" "B.Paste" "B.Mask")
      (net 2 "GND") (pinfunction "2") (pintype "passive"))
    (pad "2" smd rect (at 2.975 4.955 270) (size 1.45 4.191) (layers "F.Cu" "F.Paste" "F.Mask")
      (net 2 "GND") (pinfunction "2") (pintype "passive"))
    (pad "2" smd rect (at -2.975 4.955 270) (size 1.45 4.191) (layers "F.Cu" "F.Paste" "F.Mask")
      (net 2 "GND") (pinfunction "2") (pintype "passive"))
    (pad "2" smd rect (at -2.975 4.955 270) (size 1.45 4.191) (layers "B.Cu" "B.Paste" "B.Mask")
      (net 2 "GND") (pinfunction "2") (pintype "passive"))
  )

  (footprint "si-simulation-test-board-footprints:C_0402_1005Metric" (layer "F.Cu")
    (tedit 616D63CF)
    (at 112.39 146.415)
    (descr "Capacitor SMD 0402")
    (tags "capacitor SMD 0402")
    (property "Author" "Antmicro")
    (property "Dielectric" "X5R")
    (property "License" "Apache-2.0")
    (property "MPN" "GRM155R61H104KE14D")
    (property "Manufacturer" "Murata")
    (property "Sheetfile" "si-simulation-test-board.kicad_sch")
    (property "Sheetname" "")
    (property "Val" "100n")
    (property "Voltage" "50V")
    (attr smd)
    (fp_text reference "C2" (at 0.001 -0.7) (layer "F.SilkS") hide
      (effects (font (size 0.7 0.7) (thickness 0.15)) (justify left bottom))
    )
    (fp_text value "C_100n_0402" (at 0 1.4) (layer "F.Fab")
      (effects (font (size 0.7 0.7) (thickness 0.15)) (justify left bottom))
    )
    (fp_text user "License: Apache-2.0" (at -0.932 5.17) (layer "F.Fab") hide
      (effects (font (size 0.7 0.7) (thickness 0.15)) (justify left bottom))
    )
    (fp_text user "Author: Antmicro" (at -0.932 4.17) (layer "F.Fab") hide
      (effects (font (size 0.7 0.7) (thickness 0.15)) (justify left bottom))
    )
    (fp_text user "${REFERENCE}" (at -0.932 3.168) (layer "F.Fab") hide
      (effects (font (size 0.7 0.7) (thickness 0.15)) (justify left bottom))
    )
    (fp_rect (start -0.94 -0.47) (end 0.94 0.47) (layer "F.CrtYd") (width 0.05) (fill none))
    (fp_rect (start -0.499 -0.249) (end 0.499 0.249) (layer "F.Fab") (width 0.15) (fill none))
    (pad "1" smd roundrect (at -0.484 0) (size 0.59 0.64) (layers "F.Cu" "F.Paste" "F.Mask") (roundrect_rratio 0.25)
      (net 2 "GND") (pintype "passive"))
    (pad "2" smd roundrect (at 0.484 0) (size 0.59 0.64) (layers "F.Cu" "F.Paste" "F.Mask") (roundrect_rratio 0.25)
      (net 2 "GND") (pintype "passive"))
  )

  (footprint "si-simulation-test-board-footprints:R_0402_1005Metric" (layer "F.Cu")
    (tedit 5FD9C158)
    (at 101.45 56.007499)
    (descr "Resistor SMD 0402")
    (tags "resistor SMD 0402")
    (property "Author" "Antmicro")
    (property "License" "Apache-2.0")
    (property "MPN" "CR0402-FX-50R0GLF")
    (property "Manufacturer" "Bourns")
    (property "Sheetfile" "si-simulation-test-board.kicad_sch")
    (property "Sheetname" "")
    (property "Tolerance" "1%")
    (property "Val" "50R")
    (attr smd)
    (fp_text reference "R2" (at 0 -0.7) (layer "F.SilkS") hide
      (effects (font (size 0.7 0.7) (thickness 0.15)) (justify left bottom))
    )
    (fp_text value "R_50R_0402" (at 0 1.4) (layer "F.Fab")
      (effects (font (size 0.7 0.7) (thickness 0.15)) (justify left bottom))
    )
    (fp_text user "Author: Antmicro" (at -0.95 4.169) (layer "F.Fab") hide
      (effects (font (size 0.7 0.7) (thickness 0.15)) (justify left bottom))
    )
    (fp_text user "${REFERENCE}" (at -0.95 3.168) (layer "F.Fab") hide
      (effects (font (size 0.7 0.7) (thickness 0.15)) (justify left bottom))
    )
    (fp_text user "License: Apache-2.0" (at -0.95 5.169) (layer "F.Fab") hide
      (effects (font (size 0.7 0.7) (thickness 0.15)) (justify left bottom))
    )
    (fp_rect (start -0.93 -0.47) (end 0.93 0.47) (layer "F.CrtYd") (width 0.05) (fill none))
    (fp_rect (start -0.5 -0.25) (end 0.5 0.25) (layer "F.Fab") (width 0.15) (fill none))
    (pad "1" smd roundrect (at -0.485 0) (size 0.59 0.64) (layers "F.Cu" "F.Paste" "F.Mask") (roundrect_rratio 0.25)
      (net 11 "Net-(J6-Pad1)") (pintype "passive"))
    (pad "2" smd roundrect (at 0.485 0) (size 0.59 0.64) (layers "F.Cu" "F.Paste" "F.Mask") (roundrect_rratio 0.25)
      (net 2 "GND") (pintype "passive"))
  )

  (footprint "si-simulation-test-board-footprints:C_0402_1005Metric" (layer "F.Cu")
    (tedit 616D63CF)
    (at 126.62 146.345)
    (descr "Capacitor SMD 0402")
    (tags "capacitor SMD 0402")
    (property "Author" "Antmicro")
    (property "Dielectric" "X5R")
    (property "License" "Apache-2.0")
    (property "MPN" "GRM155R61H104KE14D")
    (property "Manufacturer" "Murata")
    (property "Sheetfile" "si-simulation-test-board.kicad_sch")
    (property "Sheetname" "")
    (property "Val" "100n")
    (property "Voltage" "50V")
    (attr smd)
    (fp_text reference "C1" (at 0.001 -0.7) (layer "F.SilkS") hide
      (effects (font (size 0.7 0.7) (thickness 0.15)) (justify left bottom))
    )
    (fp_text value "C_100n_0402" (at 0 1.4) (layer "F.Fab")
      (effects (font (size 0.7 0.7) (thickness 0.15)) (justify left bottom))
    )
    (fp_text user "${REFERENCE}" (at -0.932 3.168) (layer "F.Fab") hide
      (effects (font (size 0.7 0.7) (thickness 0.15)) (justify left bottom))
    )
    (fp_text user "Author: Antmicro" (at -0.932 4.17) (layer "F.Fab") hide
      (effects (font (size 0.7 0.7) (thickness 0.15)) (justify left bottom))
    )
    (fp_text user "License: Apache-2.0" (at -0.932 5.17) (layer "F.Fab") hide
      (effects (font (size 0.7 0.7) (thickness 0.15)) (justify left bottom))
    )
    (fp_rect (start -0.94 -0.47) (end 0.94 0.47) (layer "F.CrtYd") (width 0.05) (fill none))
    (fp_rect (start -0.499 -0.249) (end 0.499 0.249) (layer "F.Fab") (width 0.15) (fill none))
    (pad "1" smd roundrect (at -0.484 0) (size 0.59 0.64) (layers "F.Cu" "F.Paste" "F.Mask") (roundrect_rratio 0.25)
      (net 2 "GND") (pintype "passive"))
    (pad "2" smd roundrect (at 0.484 0) (size 0.59 0.64) (layers "F.Cu" "F.Paste" "F.Mask") (roundrect_rratio 0.25)
      (net 2 "GND") (pintype "passive"))
  )

  (footprint "si-simulation-test-board-footprints:RF_SMA_BoardEdge_RF2-143-T-17-50-G" (layer "F.Cu")
    (tedit 64FEFFC5)
    (at 146.68 96.0005 -90)
    (descr "RF SMA SMD board edge connector")
    (property "Author" "Antmicro")
    (property "License" "Apache-2.0")
    (property "MPN" "RF2-143-T-17-50-G")
    (property "Manufacturer" "ADAM TECH")
    (property "Sheetfile" "si-simulation-test-board.kicad_sch")
    (property "Sheetname" "")
    (attr smd)
    (fp_text reference "J10" (at -4.5 6.88) (layer "F.SilkS")
      (effects (font (size 0.7 0.7) (thickness 0.15)) (justify left bottom))
    )
    (fp_text value "Conn_SMA_RF2-143-T-17-50-G" (at 0 9.24 -90) (layer "F.Fab")
      (effects (font (size 0.7 0.7) (thickness 0.15)) (justify left bottom))
    )
    (fp_text user "Author: Antmicro" (at -4.5 11.24 -90) (layer "F.Fab") hide
      (effects (font (size 0.7 0.7) (thickness 0.15)) (justify left bottom))
    )
    (fp_text user "License: Apache-2.0" (at -4.5 12.44 -90) (layer "F.Fab") hide
      (effects (font (size 0.7 0.7) (thickness 0.15)) (justify left bottom))
    )
    (fp_text user "${REFERENCE}" (at -4.5 13.64 -90) (layer "F.Fab") hide
      (effects (font (size 0.7 0.7) (thickness 0.15)) (justify left bottom))
    )
    (fp_rect (start -3.995 -7.53) (end 3.995 7.53) (layer "B.CrtYd") (width 0.05) (fill none))
    (fp_rect (start -3.995 -7.53) (end 3.995 7.53) (layer "F.CrtYd") (width 0.05) (fill none))
    (fp_line (start -2.65 -6.375) (end -2.65 1.504) (layer "F.Fab") (width 0.15))
    (fp_line (start 0.38 2.654) (end 0.375 6.455) (layer "F.Fab") (width 0.15))
    (fp_line (start -3.174 6.455) (end -3.174 1.504) (layer "F.Fab") (width 0.15))
    (fp_line (start 3.174 2.654) (end -3.15 2.654) (layer "F.Fab") (width 0.15))
    (fp_line (start -2.375 6.455) (end -3.174 6.455) (layer "F.Fab") (width 0.15))
    (fp_line (start 0.375 6.455) (end -0.38 6.455) (layer "F.Fab") (width 0.15))
    (fp_line (start 3.174 6.455) (end 3.174 1.504) (layer "F.Fab") (width 0.15))
    (fp_line (start 3.174 1.504) (end -3.174 1.504) (layer "F.Fab") (width 0.15))
    (fp_line (start -0.38 2.654) (end -0.38 6.455) (layer "F.Fab") (width 0.15))
    (fp_line (start 2.65 -6.375) (end -2.65 -6.375) (layer "F.Fab") (width 0.15))
    (fp_line (start 3.174 6.455) (end 2.375 6.455) (layer "F.Fab") (width 0.15))
    (fp_line (start 2.375 6.455) (end 2.375 2.678) (layer "F.Fab") (width 0.15))
    (fp_line (start 2.65 -6.375) (end 2.65 1.504) (layer "F.Fab") (width 0.15))
    (fp_line (start -2.375 2.678) (end -2.375 6.455) (layer "F.Fab") (width 0.15))
    (pad "1" smd rect (at 0.007 4.955 270) (size 2.29 4.191) (layers "F.Cu" "F.Paste" "F.Mask")
      (net 6 "Net-(J10-Pad1)") (pinfunction "1") (pintype "passive"))
    (pad "2" smd rect (at -2.975 4.955 270) (size 1.45 4.191) (layers "B.Cu" "B.Paste" "B.Mask")
      (net 2 "GND") (pinfunction "2") (pintype "passive"))
    (pad "2" smd rect (at 2.975 4.955 270) (size 1.45 4.191) (layers "B.Cu" "B.Paste" "B.Mask")
      (net 2 "GND") (pinfunction "2") (pintype "passive"))
    (pad "2" smd rect (at 2.975 4.955 270) (size 1.45 4.191) (layers "F.Cu" "F.Paste" "F.Mask")
      (net 2 "GND") (pinfunction "2") (pintype "passive"))
    (pad "2" smd rect (at -2.975 4.955 270) (size 1.45 4.191) (layers "F.Cu" "F.Paste" "F.Mask")
      (net 2 "GND") (pinfunction "2") (pintype "passive"))
  )

  (footprint "si-simulation-test-board-footprints:RF_SMA_BoardEdge_RF2-143-T-17-50-G" (layer "F.Cu")
    (tedit 64FEFFC5)
    (at 91.37 105.999499 90)
    (descr "RF SMA SMD board edge connector")
    (property "Author" "Antmicro")
    (property "License" "Apache-2.0")
    (property "MPN" "RF2-143-T-17-50-G")
    (property "Manufacturer" "ADAM TECH")
    (property "Sheetfile" "si-simulation-test-board.kicad_sch")
    (property "Sheetname" "")
    (attr smd)
    (fp_text reference "J11" (at -4.5 6.88 180) (layer "F.SilkS")
      (effects (font (size 0.7 0.7) (thickness 0.15)) (justify left bottom))
    )
    (fp_text value "Conn_SMA_RF2-143-T-17-50-G" (at 0 9.24 90) (layer "F.Fab")
      (effects (font (size 0.7 0.7) (thickness 0.15)) (justify left bottom))
    )
    (fp_text user "License: Apache-2.0" (at -4.5 12.44 90) (layer "F.Fab") hide
      (effects (font (size 0.7 0.7) (thickness 0.15)) (justify left bottom))
    )
    (fp_text user "${REFERENCE}" (at -4.5 13.64 90) (layer "F.Fab") hide
      (effects (font (size 0.7 0.7) (thickness 0.15)) (justify left bottom))
    )
    (fp_text user "Author: Antmicro" (at -4.5 11.24 90) (layer "F.Fab") hide
      (effects (font (size 0.7 0.7) (thickness 0.15)) (justify left bottom))
    )
    (fp_rect (start -3.995 -7.53) (end 3.995 7.53) (layer "B.CrtYd") (width 0.05) (fill none))
    (fp_rect (start -3.995 -7.53) (end 3.995 7.53) (layer "F.CrtYd") (width 0.05) (fill none))
    (fp_line (start 3.174 1.504) (end -3.174 1.504) (layer "F.Fab") (width 0.15))
    (fp_line (start 3.174 6.455) (end 2.375 6.455) (layer "F.Fab") (width 0.15))
    (fp_line (start 3.174 6.455) (end 3.174 1.504) (layer "F.Fab") (width 0.15))
    (fp_line (start 3.174 2.654) (end -3.15 2.654) (layer "F.Fab") (width 0.15))
    (fp_line (start -0.38 2.654) (end -0.38 6.455) (layer "F.Fab") (width 0.15))
    (fp_line (start 2.65 -6.375) (end 2.65 1.504) (layer "F.Fab") (width 0.15))
    (fp_line (start -2.65 -6.375) (end -2.65 1.504) (layer "F.Fab") (width 0.15))
    (fp_line (start 0.38 2.654) (end 0.375 6.455) (layer "F.Fab") (width 0.15))
    (fp_line (start -2.375 6.455) (end -3.174 6.455) (layer "F.Fab") (width 0.15))
    (fp_line (start -2.375 2.678) (end -2.375 6.455) (layer "F.Fab") (width 0.15))
    (fp_line (start 2.375 6.455) (end 2.375 2.678) (layer "F.Fab") (width 0.15))
    (fp_line (start -3.174 6.455) (end -3.174 1.504) (layer "F.Fab") (width 0.15))
    (fp_line (start 2.65 -6.375) (end -2.65 -6.375) (layer "F.Fab") (width 0.15))
    (fp_line (start 0.375 6.455) (end -0.38 6.455) (layer "F.Fab") (width 0.15))
    (pad "1" smd rect (at 0.007 4.955 90) (size 2.29 4.191) (layers "F.Cu" "F.Paste" "F.Mask")
      (net 7 "/DIFF_P") (pinfunction "1") (pintype "passive"))
    (pad "2" smd rect (at 2.975 4.955 90) (size 1.45 4.191) (layers "B.Cu" "B.Paste" "B.Mask")
      (net 2 "GND") (pinfunction "2") (pintype "passive"))
    (pad "2" smd rect (at 2.975 4.955 90) (size 1.45 4.191) (layers "F.Cu" "F.Paste" "F.Mask")
      (net 2 "GND") (pinfunction "2") (pintype "passive"))
    (pad "2" smd rect (at -2.975 4.955 90) (size 1.45 4.191) (layers "B.Cu" "B.Paste" "B.Mask")
      (net 2 "GND") (pinfunction "2") (pintype "passive"))
    (pad "2" smd rect (at -2.975 4.955 90) (size 1.45 4.191) (layers "F.Cu" "F.Paste" "F.Mask")
      (net 2 "GND") (pinfunction "2") (pintype "passive"))
  )

  (footprint "si-simulation-test-board-footprints:RF_SMA_BoardEdge_RF2-143-T-17-50-G" (layer "F.Cu")
    (tedit 64FEFFC5)
    (at 146.68 106.0005 -90)
    (descr "RF SMA SMD board edge connector")
    (property "Author" "Antmicro")
    (property "License" "Apache-2.0")
    (property "MPN" "RF2-143-T-17-50-G")
    (property "Manufacturer" "ADAM TECH")
    (property "Sheetfile" "si-simulation-test-board.kicad_sch")
    (property "Sheetname" "")
    (attr smd)
    (fp_text reference "J13" (at -4.5 6.88) (layer "F.SilkS")
      (effects (font (size 0.7 0.7) (thickness 0.15)) (justify left bottom))
    )
    (fp_text value "Conn_SMA_RF2-143-T-17-50-G" (at 0 9.24 -90) (layer "F.Fab")
      (effects (font (size 0.7 0.7) (thickness 0.15)) (justify left bottom))
    )
    (fp_text user "${REFERENCE}" (at -4.5 13.64 -90) (layer "F.Fab") hide
      (effects (font (size 0.7 0.7) (thickness 0.15)) (justify left bottom))
    )
    (fp_text user "Author: Antmicro" (at -4.5 11.24 -90) (layer "F.Fab") hide
      (effects (font (size 0.7 0.7) (thickness 0.15)) (justify left bottom))
    )
    (fp_text user "License: Apache-2.0" (at -4.5 12.44 -90) (layer "F.Fab") hide
      (effects (font (size 0.7 0.7) (thickness 0.15)) (justify left bottom))
    )
    (fp_rect (start -3.995 -7.53) (end 3.995 7.53) (layer "B.CrtYd") (width 0.05) (fill none))
    (fp_rect (start -3.995 -7.53) (end 3.995 7.53) (layer "F.CrtYd") (width 0.05) (fill none))
    (fp_line (start 3.174 1.504) (end -3.174 1.504) (layer "F.Fab") (width 0.15))
    (fp_line (start -3.174 6.455) (end -3.174 1.504) (layer "F.Fab") (width 0.15))
    (fp_line (start 2.65 -6.375) (end -2.65 -6.375) (layer "F.Fab") (width 0.15))
    (fp_line (start 3.174 6.455) (end 3.174 1.504) (layer "F.Fab") (width 0.15))
    (fp_line (start 0.375 6.455) (end -0.38 6.455) (layer "F.Fab") (width 0.15))
    (fp_line (start -2.375 2.678) (end -2.375 6.455) (layer "F.Fab") (width 0.15))
    (fp_line (start 2.65 -6.375) (end 2.65 1.504) (layer "F.Fab") (width 0.15))
    (fp_line (start 2.375 6.455) (end 2.375 2.678) (layer "F.Fab") (width 0.15))
    (fp_line (start -2.65 -6.375) (end -2.65 1.504) (layer "F.Fab") (width 0.15))
    (fp_line (start -0.38 2.654) (end -0.38 6.455) (layer "F.Fab") (width 0.15))
    (fp_line (start 3.174 2.654) (end -3.15 2.654) (layer "F.Fab") (width 0.15))
    (fp_line (start 0.38 2.654) (end 0.375 6.455) (layer "F.Fab") (width 0.15))
    (fp_line (start -2.375 6.455) (end -3.174 6.455) (layer "F.Fab") (width 0.15))
    (fp_line (start 3.174 6.455) (end 2.375 6.455) (layer "F.Fab") (width 0.15))
    (pad "1" smd rect (at 0.007 4.955 270) (size 2.29 4.191) (layers "F.Cu" "F.Paste" "F.Mask")
      (net 7 "/DIFF_P") (pinfunction "1") (pintype "passive"))
    (pad "2" smd rect (at -2.975 4.955 270) (size 1.45 4.191) (layers "B.Cu" "B.Paste" "B.Mask")
      (net 2 "GND") (pinfunction "2") (pintype "passive"))
    (pad "2" smd rect (at 2.975 4.955 270) (size 1.45 4.191) (layers "B.Cu" "B.Paste" "B.Mask")
      (net 2 "GND") (pinfunction "2") (pintype "passive"))
    (pad "2" smd rect (at -2.975 4.955 270) (size 1.45 4.191) (layers "F.Cu" "F.Paste" "F.Mask")
      (net 2 "GND") (pinfunction "2") (pintype "passive"))
    (pad "2" smd rect (at 2.975 4.955 270) (size 1.45 4.191) (layers "F.Cu" "F.Paste" "F.Mask")
      (net 2 "GND") (pinfunction "2") (pintype "passive"))
  )

  (footprint "si-simulation-test-board-footprints:RF_SMA_BoardEdge_RF2-143-T-17-50-G" (layer "F.Cu")
    (tedit 64FEFFC5)
    (at 91.37 137.614499 90)
    (descr "RF SMA SMD board edge connector")
    (property "Author" "Antmicro")
    (property "License" "Apache-2.0")
    (property "MPN" "RF2-143-T-17-50-G")
    (property "Manufacturer" "ADAM TECH")
    (property "Sheetfile" "si-simulation-test-board.kicad_sch")
    (property "Sheetname" "")
    (attr smd)
    (fp_text reference "J15" (at -4.5 6.88 180) (layer "F.SilkS")
      (effects (font (size 0.7 0.7) (thickness 0.15)) (justify left bottom))
    )
    (fp_text value "Conn_SMA_RF2-143-T-17-50-G" (at 0 9.24 90) (layer "F.Fab")
      (effects (font (size 0.7 0.7) (thickness 0.15)) (justify left bottom))
    )
    (fp_text user "License: Apache-2.0" (at -4.5 12.44 90) (layer "F.Fab") hide
      (effects (font (size 0.7 0.7) (thickness 0.15)) (justify left bottom))
    )
    (fp_text user "Author: Antmicro" (at -4.5 11.24 90) (layer "F.Fab") hide
      (effects (font (size 0.7 0.7) (thickness 0.15)) (justify left bottom))
    )
    (fp_text user "${REFERENCE}" (at -4.5 13.64 90) (layer "F.Fab") hide
      (effects (font (size 0.7 0.7) (thickness 0.15)) (justify left bottom))
    )
    (fp_rect (start -3.995 -7.53) (end 3.995 7.53) (layer "B.CrtYd") (width 0.05) (fill none))
    (fp_rect (start -3.995 -7.53) (end 3.995 7.53) (layer "F.CrtYd") (width 0.05) (fill none))
    (fp_line (start 3.174 6.455) (end 3.174 1.504) (layer "F.Fab") (width 0.15))
    (fp_line (start 3.174 6.455) (end 2.375 6.455) (layer "F.Fab") (width 0.15))
    (fp_line (start -2.375 6.455) (end -3.174 6.455) (layer "F.Fab") (width 0.15))
    (fp_line (start 3.174 1.504) (end -3.174 1.504) (layer "F.Fab") (width 0.15))
    (fp_line (start 3.174 2.654) (end -3.15 2.654) (layer "F.Fab") (width 0.15))
    (fp_line (start -2.65 -6.375) (end -2.65 1.504) (layer "F.Fab") (width 0.15))
    (fp_line (start -2.375 2.678) (end -2.375 6.455) (layer "F.Fab") (width 0.15))
    (fp_line (start 2.375 6.455) (end 2.375 2.678) (layer "F.Fab") (width 0.15))
    (fp_line (start 2.65 -6.375) (end -2.65 -6.375) (layer "F.Fab") (width 0.15))
    (fp_line (start 0.38 2.654) (end 0.375 6.455) (layer "F.Fab") (width 0.15))
    (fp_line (start -0.38 2.654) (end -0.38 6.455) (layer "F.Fab") (width 0.15))
    (fp_line (start 0.375 6.455) (end -0.38 6.455) (layer "F.Fab") (width 0.15))
    (fp_line (start -3.174 6.455) (end -3.174 1.504) (layer "F.Fab") (width 0.15))
    (fp_line (start 2.65 -6.375) (end 2.65 1.504) (layer "F.Fab") (width 0.15))
    (pad "1" smd rect (at 0.007 4.955 90) (size 2.29 4.191) (layers "F.Cu" "F.Paste" "F.Mask")
      (net 9 "Net-(J15-Pad1)") (pinfunction "1") (pintype "passive"))
    (pad "2" smd rect (at -2.975 4.955 90) (size 1.45 4.191) (layers "F.Cu" "F.Paste" "F.Mask")
      (net 2 "GND") (pinfunction "2") (pintype "passive"))
    (pad "2" smd rect (at 2.975 4.955 90) (size 1.45 4.191) (layers "B.Cu" "B.Paste" "B.Mask")
      (net 2 "GND") (pinfunction "2") (pintype "passive"))
    (pad "2" smd rect (at -2.975 4.955 90) (size 1.45 4.191) (layers "B.Cu" "B.Paste" "B.Mask")
      (net 2 "GND") (pinfunction "2") (pintype "passive"))
    (pad "2" smd rect (at 2.975 4.955 90) (size 1.45 4.191) (layers "F.Cu" "F.Paste" "F.Mask")
      (net 2 "GND") (pinfunction "2") (pintype "passive"))
  )

  (footprint "si-simulation-test-board-footprints:R_0201" (layer "F.Cu")
    (tedit 5FBD1D44)
    (at 116.144 99.100001 180)
    (descr "Resistor SMD 0201")
    (tags "resistor SMD 0201")
    (property "Author" "Antmicro")
    (property "DNP" "DNP")
    (property "License" "Apache-2.0")
    (property "MPN" "CR0201-FX-0R00GLF")
    (property "Manufacturer" "Bourns")
    (property "Sheetfile" "si-simulation-test-board.kicad_sch")
    (property "Sheetname" "")
    (property "Tolerance" "1%")
    (property "Val" "0R")
    (attr smd)
    (fp_text reference "R4" (at 0 -0.5) (layer "F.SilkS") hide
      (effects (font (size 0.7 0.7) (thickness 0.15)) (justify right bottom))
    )
    (fp_text value "R_0R_0201" (at 0 1.25) (layer "F.Fab")
      (effects (font (size 0.7 0.7) (thickness 0.15)) (justify right bottom))
    )
    (fp_text user "Author: Antmicro" (at -0.71 5.25) (layer "F.Fab") hide
      (effects (font (size 0.7 0.7) (thickness 0.15)) (justify right bottom))
    )
    (fp_text user "${REFERENCE}" (at -0.71 3.25) (layer "F.Fab") hide
      (effects (font (size 0.7 0.7) (thickness 0.15)) (justify right bottom))
    )
    (fp_text user "License: Apache-2.0" (at -0.71 4.25) (layer "F.Fab") hide
      (effects (font (size 0.7 0.7) (thickness 0.15)) (justify right bottom))
    )
    (fp_rect (start -0.71 -0.36) (end 0.71 0.36) (layer "F.CrtYd") (width 0.05) (fill none))
    (fp_rect (start -0.3 -0.15) (end 0.298 0.148) (layer "F.Fab") (width 0.15) (fill none))
    (pad "" smd roundrect (at -0.346 0 180) (size 0.318 0.36) (layers "F.Paste") (roundrect_rratio 0.25))
    (pad "" smd roundrect (at 0.344 0 180) (size 0.318 0.36) (layers "F.Paste") (roundrect_rratio 0.25))
    (pad "1" smd roundrect (at -0.32 0 180) (size 0.46 0.4) (layers "F.Cu" "F.Mask") (roundrect_rratio 0.25)
      (net 2 "GND") (pintype "passive"))
    (pad "2" smd roundrect (at 0.32 0 180) (size 0.46 0.4) (layers "F.Cu" "F.Mask") (roundrect_rratio 0.25)
      (net 6 "Net-(J10-Pad1)") (pintype "passive"))
  )

  (footprint "si-simulation-test-board-footprints:RF_SMA_BoardEdge_RF2-143-T-17-50-G" (layer "F.Cu")
    (tedit 64FEFFC5)
    (at 91.32 75.999499 90)
    (descr "RF SMA SMD board edge connector")
    (property "Author" "Antmicro")
    (property "License" "Apache-2.0")
    (property "MPN" "RF2-143-T-17-50-G")
    (property "Manufacturer" "ADAM TECH")
    (property "Sheetfile" "si-simulation-test-board.kicad_sch")
    (property "Sheetname" "")
    (attr smd)
    (fp_text reference "J1" (at -4.5 6.88 180) (layer "F.SilkS")
      (effects (font (size 0.7 0.7) (thickness 0.15)) (justify left bottom))
    )
    (fp_text value "Conn_SMA_RF2-143-T-17-50-G" (at 0 9.24 90) (layer "F.Fab")
      (effects (font (size 0.7 0.7) (thickness 0.15)) (justify left bottom))
    )
    (fp_text user "${REFERENCE}" (at -4.5 13.64 90) (layer "F.Fab") hide
      (effects (font (size 0.7 0.7) (thickness 0.15)) (justify left bottom))
    )
    (fp_text user "Author: Antmicro" (at -4.5 11.24 90) (layer "F.Fab") hide
      (effects (font (size 0.7 0.7) (thickness 0.15)) (justify left bottom))
    )
    (fp_text user "License: Apache-2.0" (at -4.5 12.44 90) (layer "F.Fab") hide
      (effects (font (size 0.7 0.7) (thickness 0.15)) (justify left bottom))
    )
    (fp_rect (start -3.995 -7.53) (end 3.995 7.53) (layer "B.CrtYd") (width 0.05) (fill none))
    (fp_rect (start -3.995 -7.53) (end 3.995 7.53) (layer "F.CrtYd") (width 0.05) (fill none))
    (fp_line (start -2.375 2.678) (end -2.375 6.455) (layer "F.Fab") (width 0.15))
    (fp_line (start 2.65 -6.375) (end 2.65 1.504) (layer "F.Fab") (width 0.15))
    (fp_line (start -0.38 2.654) (end -0.38 6.455) (layer "F.Fab") (width 0.15))
    (fp_line (start 3.174 6.455) (end 2.375 6.455) (layer "F.Fab") (width 0.15))
    (fp_line (start 3.174 1.504) (end -3.174 1.504) (layer "F.Fab") (width 0.15))
    (fp_line (start -2.65 -6.375) (end -2.65 1.504) (layer "F.Fab") (width 0.15))
    (fp_line (start -3.174 6.455) (end -3.174 1.504) (layer "F.Fab") (width 0.15))
    (fp_line (start 3.174 2.654) (end -3.15 2.654) (layer "F.Fab") (width 0.15))
    (fp_line (start 2.65 -6.375) (end -2.65 -6.375) (layer "F.Fab") (width 0.15))
    (fp_line (start 0.375 6.455) (end -0.38 6.455) (layer "F.Fab") (width 0.15))
    (fp_line (start 3.174 6.455) (end 3.174 1.504) (layer "F.Fab") (width 0.15))
    (fp_line (start 0.38 2.654) (end 0.375 6.455) (layer "F.Fab") (width 0.15))
    (fp_line (start -2.375 6.455) (end -3.174 6.455) (layer "F.Fab") (width 0.15))
    (fp_line (start 2.375 6.455) (end 2.375 2.678) (layer "F.Fab") (width 0.15))
    (pad "1" smd rect (at 0.007 4.955 90) (size 2.29 4.191) (layers "F.Cu" "F.Paste" "F.Mask")
      (net 1 "Net-(J1-Pad1)") (pinfunction "1") (pintype "passive"))
    (pad "2" smd rect (at -2.975 4.955 90) (size 1.45 4.191) (layers "B.Cu" "B.Paste" "B.Mask")
      (net 2 "GND") (pinfunction "2") (pintype "passive"))
    (pad "2" smd rect (at -2.975 4.955 90) (size 1.45 4.191) (layers "F.Cu" "F.Paste" "F.Mask")
      (net 2 "GND") (pinfunction "2") (pintype "passive"))
    (pad "2" smd rect (at 2.975 4.955 90) (size 1.45 4.191) (layers "B.Cu" "B.Paste" "B.Mask")
      (net 2 "GND") (pinfunction "2") (pintype "passive"))
    (pad "2" smd rect (at 2.975 4.955 90) (size 1.45 4.191) (layers "F.Cu" "F.Paste" "F.Mask")
      (net 2 "GND") (pinfunction "2") (pintype "passive"))
  )

  (footprint "si-simulation-test-board-footprints:RF_SMA_BoardEdge_RF2-143-T-17-50-G" (layer "F.Cu")
    (tedit 64FEFFC5)
    (at 146.63 76.0005 -90)
    (descr "RF SMA SMD board edge connector")
    (property "Author" "Antmicro")
    (property "License" "Apache-2.0")
    (property "MPN" "RF2-143-T-17-50-G")
    (property "Manufacturer" "ADAM TECH")
    (property "Sheetfile" "si-simulation-test-board.kicad_sch")
    (property "Sheetname" "")
    (attr smd)
    (fp_text reference "J2" (at -4.5 6.88) (layer "F.SilkS")
      (effects (font (size 0.7 0.7) (thickness 0.15)) (justify left bottom))
    )
    (fp_text value "Conn_SMA_RF2-143-T-17-50-G" (at 0 9.24 -90) (layer "F.Fab")
      (effects (font (size 0.7 0.7) (thickness 0.15)) (justify left bottom))
    )
    (fp_text user "License: Apache-2.0" (at -4.5 12.44 -90) (layer "F.Fab") hide
      (effects (font (size 0.7 0.7) (thickness 0.15)) (justify left bottom))
    )
    (fp_text user "Author: Antmicro" (at -4.5 11.24 -90) (layer "F.Fab") hide
      (effects (font (size 0.7 0.7) (thickness 0.15)) (justify left bottom))
    )
    (fp_text user "${REFERENCE}" (at -4.5 13.64 -90) (layer "F.Fab") hide
      (effects (font (size 0.7 0.7) (thickness 0.15)) (justify left bottom))
    )
    (fp_rect (start -3.995 -7.53) (end 3.995 7.53) (layer "B.CrtYd") (width 0.05) (fill none))
    (fp_rect (start -3.995 -7.53) (end 3.995 7.53) (layer "F.CrtYd") (width 0.05) (fill none))
    (fp_line (start 0.375 6.455) (end -0.38 6.455) (layer "F.Fab") (width 0.15))
    (fp_line (start -2.65 -6.375) (end -2.65 1.504) (layer "F.Fab") (width 0.15))
    (fp_line (start 2.65 -6.375) (end 2.65 1.504) (layer "F.Fab") (width 0.15))
    (fp_line (start 2.375 6.455) (end 2.375 2.678) (layer "F.Fab") (width 0.15))
    (fp_line (start 0.38 2.654) (end 0.375 6.455) (layer "F.Fab") (width 0.15))
    (fp_line (start 3.174 6.455) (end 3.174 1.504) (layer "F.Fab") (width 0.15))
    (fp_line (start -2.375 6.455) (end -3.174 6.455) (layer "F.Fab") (width 0.15))
    (fp_line (start 3.174 2.654) (end -3.15 2.654) (layer "F.Fab") (width 0.15))
    (fp_line (start -0.38 2.654) (end -0.38 6.455) (layer "F.Fab") (width 0.15))
    (fp_line (start -2.375 2.678) (end -2.375 6.455) (layer "F.Fab") (width 0.15))
    (fp_line (start 3.174 1.504) (end -3.174 1.504) (layer "F.Fab") (width 0.15))
    (fp_line (start 3.174 6.455) (end 2.375 6.455) (layer "F.Fab") (width 0.15))
    (fp_line (start 2.65 -6.375) (end -2.65 -6.375) (layer "F.Fab") (width 0.15))
    (fp_line (start -3.174 6.455) (end -3.174 1.504) (layer "F.Fab") (width 0.15))
    (pad "1" smd rect (at 0.007 4.955 270) (size 2.29 4.191) (layers "F.Cu" "F.Paste" "F.Mask")
      (net 1 "Net-(J1-Pad1)") (pinfunction "1") (pintype "passive"))
    (pad "2" smd rect (at -2.975 4.955 270) (size 1.45 4.191) (layers "F.Cu" "F.Paste" "F.Mask")
      (net 2 "GND") (pinfunction "2") (pintype "passive"))
    (pad "2" smd rect (at -2.975 4.955 270) (size 1.45 4.191) (layers "B.Cu" "B.Paste" "B.Mask")
      (net 2 "GND") (pinfunction "2") (pintype "passive"))
    (pad "2" smd rect (at 2.975 4.955 270) (size 1.45 4.191) (layers "B.Cu" "B.Paste" "B.Mask")
      (net 2 "GND") (pinfunction "2") (pintype "passive"))
    (pad "2" smd rect (at 2.975 4.955 270) (size 1.45 4.191) (layers "F.Cu" "F.Paste" "F.Mask")
      (net 2 "GND") (pinfunction "2") (pintype "passive"))
  )

  (footprint "si-simulation-test-board-footprints:RF_SMA_BoardEdge_RF2-143-T-17-50-G" (layer "F.Cu")
    (tedit 64FEFFC5)
    (at 91.37 117.299499 90)
    (descr "RF SMA SMD board edge connector")
    (property "Author" "Antmicro")
    (property "License" "Apache-2.0")
    (property "MPN" "RF2-143-T-17-50-G")
    (property "Manufacturer" "ADAM TECH")
    (property "Sheetfile" "si-simulation-test-board.kicad_sch")
    (property "Sheetname" "")
    (attr smd)
    (fp_text reference "J12" (at -4.5 6.88 180) (layer "F.SilkS")
      (effects (font (size 0.7 0.7) (thickness 0.15)) (justify left bottom))
    )
    (fp_text value "Conn_SMA_RF2-143-T-17-50-G" (at 0 9.24 90) (layer "F.Fab")
      (effects (font (size 0.7 0.7) (thickness 0.15)) (justify left bottom))
    )
    (fp_text user "${REFERENCE}" (at -4.5 13.64 90) (layer "F.Fab") hide
      (effects (font (size 0.7 0.7) (thickness 0.15)) (justify left bottom))
    )
    (fp_text user "License: Apache-2.0" (at -4.5 12.44 90) (layer "F.Fab") hide
      (effects (font (size 0.7 0.7) (thickness 0.15)) (justify left bottom))
    )
    (fp_text user "Author: Antmicro" (at -4.5 11.24 90) (layer "F.Fab") hide
      (effects (font (size 0.7 0.7) (thickness 0.15)) (justify left bottom))
    )
    (fp_rect (start -3.995 -7.53) (end 3.995 7.53) (layer "B.CrtYd") (width 0.05) (fill none))
    (fp_rect (start -3.995 -7.53) (end 3.995 7.53) (layer "F.CrtYd") (width 0.05) (fill none))
    (fp_line (start -3.174 6.455) (end -3.174 1.504) (layer "F.Fab") (width 0.15))
    (fp_line (start 3.174 2.654) (end -3.15 2.654) (layer "F.Fab") (width 0.15))
    (fp_line (start 2.65 -6.375) (end -2.65 -6.375) (layer "F.Fab") (width 0.15))
    (fp_line (start -2.65 -6.375) (end -2.65 1.504) (layer "F.Fab") (width 0.15))
    (fp_line (start -2.375 2.678) (end -2.375 6.455) (layer "F.Fab") (width 0.15))
    (fp_line (start -2.375 6.455) (end -3.174 6.455) (layer "F.Fab") (width 0.15))
    (fp_line (start 2.65 -6.375) (end 2.65 1.504) (layer "F.Fab") (width 0.15))
    (fp_line (start 2.375 6.455) (end 2.375 2.678) (layer "F.Fab") (width 0.15))
    (fp_line (start -0.38 2.654) (end -0.38 6.455) (layer "F.Fab") (width 0.15))
    (fp_line (start 3.174 6.455) (end 2.375 6.455) (layer "F.Fab") (width 0.15))
    (fp_line (start 3.174 1.504) (end -3.174 1.504) (layer "F.Fab") (width 0.15))
    (fp_line (start 3.174 6.455) (end 3.174 1.504) (layer "F.Fab") (width 0.15))
    (fp_line (start 0.375 6.455) (end -0.38 6.455) (layer "F.Fab") (width 0.15))
    (fp_line (start 0.38 2.654) (end 0.375 6.455) (layer "F.Fab") (width 0.15))
    (pad "1" smd rect (at 0.007 4.955 90) (size 2.29 4.191) (layers "F.Cu" "F.Paste" "F.Mask")
      (net 8 "/DIFF_N") (pinfunction "1") (pintype "passive"))
    (pad "2" smd rect (at -2.975 4.955 90) (size 1.45 4.191) (layers "B.Cu" "B.Paste" "B.Mask")
      (net 2 "GND") (pinfunction "2") (pintype "passive"))
    (pad "2" smd rect (at 2.975 4.955 90) (size 1.45 4.191) (layers "F.Cu" "F.Paste" "F.Mask")
      (net 2 "GND") (pinfunction "2") (pintype "passive"))
    (pad "2" smd rect (at -2.975 4.955 90) (size 1.45 4.191) (layers "F.Cu" "F.Paste" "F.Mask")
      (net 2 "GND") (pinfunction "2") (pintype "passive"))
    (pad "2" smd rect (at 2.975 4.955 90) (size 1.45 4.191) (layers "B.Cu" "B.Paste" "B.Mask")
      (net 2 "GND") (pinfunction "2") (pintype "passive"))
  )

  (footprint "si-simulation-test-board-footprints:RF_SMA_BoardEdge_RF2-143-T-17-50-G" (layer "F.Cu")
    (tedit 64FEFFC5)
    (at 91.37 127.614499 90)
    (descr "RF SMA SMD board edge connector")
    (property "Author" "Antmicro")
    (property "License" "Apache-2.0")
    (property "MPN" "RF2-143-T-17-50-G")
    (property "Manufacturer" "ADAM TECH")
    (property "Sheetfile" "si-simulation-test-board.kicad_sch")
    (property "Sheetname" "")
    (attr smd)
    (fp_text reference "J19" (at -4.5 6.88 180) (layer "F.SilkS")
      (effects (font (size 0.7 0.7) (thickness 0.15)) (justify left bottom))
    )
    (fp_text value "Conn_SMA_RF2-143-T-17-50-G" (at 0 9.24 90) (layer "F.Fab")
      (effects (font (size 0.7 0.7) (thickness 0.15)) (justify left bottom))
    )
    (fp_text user "License: Apache-2.0" (at -4.5 12.44 90) (layer "F.Fab") hide
      (effects (font (size 0.7 0.7) (thickness 0.15)) (justify left bottom))
    )
    (fp_text user "Author: Antmicro" (at -4.5 11.24 90) (layer "F.Fab") hide
      (effects (font (size 0.7 0.7) (thickness 0.15)) (justify left bottom))
    )
    (fp_text user "${REFERENCE}" (at -4.5 13.64 90) (layer "F.Fab") hide
      (effects (font (size 0.7 0.7) (thickness 0.15)) (justify left bottom))
    )
    (fp_rect (start -3.995 -7.53) (end 3.995 7.53) (layer "B.CrtYd") (width 0.05) (fill none))
    (fp_rect (start -3.995 -7.53) (end 3.995 7.53) (layer "F.CrtYd") (width 0.05) (fill none))
    (fp_line (start 2.375 6.455) (end 2.375 2.678) (layer "F.Fab") (width 0.15))
    (fp_line (start 2.65 -6.375) (end -2.65 -6.375) (layer "F.Fab") (width 0.15))
    (fp_line (start -0.38 2.654) (end -0.38 6.455) (layer "F.Fab") (width 0.15))
    (fp_line (start 3.174 1.504) (end -3.174 1.504) (layer "F.Fab") (width 0.15))
    (fp_line (start -2.65 -6.375) (end -2.65 1.504) (layer "F.Fab") (width 0.15))
    (fp_line (start -2.375 2.678) (end -2.375 6.455) (layer "F.Fab") (width 0.15))
    (fp_line (start 0.38 2.654) (end 0.375 6.455) (layer "F.Fab") (width 0.15))
    (fp_line (start 3.174 6.455) (end 2.375 6.455) (layer "F.Fab") (width 0.15))
    (fp_line (start 3.174 2.654) (end -3.15 2.654) (layer "F.Fab") (width 0.15))
    (fp_line (start -2.375 6.455) (end -3.174 6.455) (layer "F.Fab") (width 0.15))
    (fp_line (start 3.174 6.455) (end 3.174 1.504) (layer "F.Fab") (width 0.15))
    (fp_line (start 0.375 6.455) (end -0.38 6.455) (layer "F.Fab") (width 0.15))
    (fp_line (start -3.174 6.455) (end -3.174 1.504) (layer "F.Fab") (width 0.15))
    (fp_line (start 2.65 -6.375) (end 2.65 1.504) (layer "F.Fab") (width 0.15))
    (pad "1" smd rect (at 0.007 4.955 90) (size 2.29 4.191) (layers "F.Cu" "F.Paste" "F.Mask")
      (net 2 "GND") (pinfunction "1") (pintype "passive"))
    (pad "2" smd rect (at 2.975 4.955 90) (size 1.45 4.191) (layers "F.Cu" "F.Paste" "F.Mask")
      (net 2 "GND") (pinfunction "2") (pintype "passive"))
    (pad "2" smd rect (at 2.975 4.955 90) (size 1.45 4.191) (layers "B.Cu" "B.Paste" "B.Mask")
      (net 2 "GND") (pinfunction "2") (pintype "passive"))
    (pad "2" smd rect (at -2.975 4.955 90) (size 1.45 4.191) (layers "F.Cu" "F.Paste" "F.Mask")
      (net 2 "GND") (pinfunction "2") (pintype "passive"))
    (pad "2" smd rect (at -2.975 4.955 90) (size 1.45 4.191) (layers "B.Cu" "B.Paste" "B.Mask")
      (net 2 "GND") (pinfunction "2") (pintype "passive"))
  )

  (footprint "si-simulation-test-board-footprints:RF_SMA_BoardEdge_RF2-143-T-17-50-G" (layer "F.Cu")
    (tedit 64FEFFC5)
    (at 146.63 56.0005 -90)
    (descr "RF SMA SMD board edge connector")
    (property "Author" "Antmicro")
    (property "License" "Apache-2.0")
    (property "MPN" "RF2-143-T-17-50-G")
    (property "Manufacturer" "ADAM TECH")
    (property "Sheetfile" "si-simulation-test-board.kicad_sch")
    (property "Sheetname" "")
    (attr smd)
    (fp_text reference "J5" (at -4.5 6.88) (layer "F.SilkS")
      (effects (font (size 0.7 0.7) (thickness 0.15)) (justify left bottom))
    )
    (fp_text value "Conn_SMA_RF2-143-T-17-50-G" (at 0 9.24 -90) (layer "F.Fab")
      (effects (font (size 0.7 0.7) (thickness 0.15)) (justify left bottom))
    )
    (fp_text user "Author: Antmicro" (at -4.5 11.24 -90) (layer "F.Fab") hide
      (effects (font (size 0.7 0.7) (thickness 0.15)) (justify left bottom))
    )
    (fp_text user "License: Apache-2.0" (at -4.5 12.44 -90) (layer "F.Fab") hide
      (effects (font (size 0.7 0.7) (thickness 0.15)) (justify left bottom))
    )
    (fp_text user "${REFERENCE}" (at -4.5 13.64 -90) (layer "F.Fab") hide
      (effects (font (size 0.7 0.7) (thickness 0.15)) (justify left bottom))
    )
    (fp_rect (start -3.995 -7.53) (end 3.995 7.53) (layer "B.CrtYd") (width 0.05) (fill none))
    (fp_rect (start -3.995 -7.53) (end 3.995 7.53) (layer "F.CrtYd") (width 0.05) (fill none))
    (fp_line (start -3.174 6.455) (end -3.174 1.504) (layer "F.Fab") (width 0.15))
    (fp_line (start 0.38 2.654) (end 0.375 6.455) (layer "F.Fab") (width 0.15))
    (fp_line (start 2.65 -6.375) (end -2.65 -6.375) (layer "F.Fab") (width 0.15))
    (fp_line (start 3.174 1.504) (end -3.174 1.504) (layer "F.Fab") (width 0.15))
    (fp_line (start -2.65 -6.375) (end -2.65 1.504) (layer "F.Fab") (width 0.15))
    (fp_line (start -2.375 6.455) (end -3.174 6.455) (layer "F.Fab") (width 0.15))
    (fp_line (start -2.375 2.678) (end -2.375 6.455) (layer "F.Fab") (width 0.15))
    (fp_line (start 2.65 -6.375) (end 2.65 1.504) (layer "F.Fab") (width 0.15))
    (fp_line (start 0.375 6.455) (end -0.38 6.455) (layer "F.Fab") (width 0.15))
    (fp_line (start 2.375 6.455) (end 2.375 2.678) (layer "F.Fab") (width 0.15))
    (fp_line (start 3.174 6.455) (end 3.174 1.504) (layer "F.Fab") (width 0.15))
    (fp_line (start 3.174 2.654) (end -3.15 2.654) (layer "F.Fab") (width 0.15))
    (fp_line (start -0.38 2.654) (end -0.38 6.455) (layer "F.Fab") (width 0.15))
    (fp_line (start 3.174 6.455) (end 2.375 6.455) (layer "F.Fab") (width 0.15))
    (pad "1" smd rect (at 0.007 4.955 270) (size 2.29 4.191) (layers "F.Cu" "F.Paste" "F.Mask")
      (net 4 "Net-(AE1-Pad1)") (pinfunction "1") (pintype "passive"))
    (pad "2" smd rect (at 2.975 4.955 270) (size 1.45 4.191) (layers "B.Cu" "B.Paste" "B.Mask")
      (net 2 "GND") (pinfunction "2") (pintype "passive"))
    (pad "2" smd rect (at -2.975 4.955 270) (size 1.45 4.191) (layers "B.Cu" "B.Paste" "B.Mask")
      (net 2 "GND") (pinfunction "2") (pintype "passive"))
    (pad "2" smd rect (at -2.975 4.955 270) (size 1.45 4.191) (layers "F.Cu" "F.Paste" "F.Mask")
      (net 2 "GND") (pinfunction "2") (pintype "passive"))
    (pad "2" smd rect (at 2.975 4.955 270) (size 1.45 4.191) (layers "F.Cu" "F.Paste" "F.Mask")
      (net 2 "GND") (pinfunction "2") (pintype "passive"))
  )

  (footprint "si-simulation-test-board-footprints:RF_SMA_BoardEdge_RF2-143-T-17-50-G" (layer "F.Cu")
    (tedit 64FEFFC5)
    (at 91.32 55.999499 90)
    (descr "RF SMA SMD board edge connector")
    (property "Author" "Antmicro")
    (property "License" "Apache-2.0")
    (property "MPN" "RF2-143-T-17-50-G")
    (property "Manufacturer" "ADAM TECH")
    (property "Sheetfile" "si-simulation-test-board.kicad_sch")
    (property "Sheetname" "")
    (attr smd)
    (fp_text reference "J6" (at -4.5 6.88 180) (layer "F.SilkS")
      (effects (font (size 0.7 0.7) (thickness 0.15)) (justify left bottom))
    )
    (fp_text value "Conn_SMA_RF2-143-T-17-50-G" (at 0 9.24 90) (layer "F.Fab")
      (effects (font (size 0.7 0.7) (thickness 0.15)) (justify left bottom))
    )
    (fp_text user "${REFERENCE}" (at -4.5 13.64 90) (layer "F.Fab") hide
      (effects (font (size 0.7 0.7) (thickness 0.15)) (justify left bottom))
    )
    (fp_text user "Author: Antmicro" (at -4.5 11.24 90) (layer "F.Fab") hide
      (effects (font (size 0.7 0.7) (thickness 0.15)) (justify left bottom))
    )
    (fp_text user "License: Apache-2.0" (at -4.5 12.44 90) (layer "F.Fab") hide
      (effects (font (size 0.7 0.7) (thickness 0.15)) (justify left bottom))
    )
    (fp_rect (start -3.995 -7.53) (end 3.995 7.53) (layer "B.CrtYd") (width 0.05) (fill none))
    (fp_rect (start -3.995 -7.53) (end 3.995 7.53) (layer "F.CrtYd") (width 0.05) (fill none))
    (fp_line (start -3.174 6.455) (end -3.174 1.504) (layer "F.Fab") (width 0.15))
    (fp_line (start -0.38 2.654) (end -0.38 6.455) (layer "F.Fab") (width 0.15))
    (fp_line (start 3.174 2.654) (end -3.15 2.654) (layer "F.Fab") (width 0.15))
    (fp_line (start -2.65 -6.375) (end -2.65 1.504) (layer "F.Fab") (width 0.15))
    (fp_line (start 3.174 6.455) (end 3.174 1.504) (layer "F.Fab") (width 0.15))
    (fp_line (start 0.375 6.455) (end -0.38 6.455) (layer "F.Fab") (width 0.15))
    (fp_line (start 2.65 -6.375) (end 2.65 1.504) (layer "F.Fab") (width 0.15))
    (fp_line (start 0.38 2.654) (end 0.375 6.455) (layer "F.Fab") (width 0.15))
    (fp_line (start 2.375 6.455) (end 2.375 2.678) (layer "F.Fab") (width 0.15))
    (fp_line (start 2.65 -6.375) (end -2.65 -6.375) (layer "F.Fab") (width 0.15))
    (fp_line (start -2.375 2.678) (end -2.375 6.455) (layer "F.Fab") (width 0.15))
    (fp_line (start -2.375 6.455) (end -3.174 6.455) (layer "F.Fab") (width 0.15))
    (fp_line (start 3.174 1.504) (end -3.174 1.504) (layer "F.Fab") (width 0.15))
    (fp_line (start 3.174 6.455) (end 2.375 6.455) (layer "F.Fab") (width 0.15))
    (pad "1" smd rect (at 0.007 4.955 90) (size 2.29 4.191) (layers "F.Cu" "F.Paste" "F.Mask")
      (net 11 "Net-(J6-Pad1)") (pinfunction "1") (pintype "passive"))
    (pad "2" smd rect (at 2.975 4.955 90) (size 1.45 4.191) (layers "F.Cu" "F.Paste" "F.Mask")
      (net 2 "GND") (pinfunction "2") (pintype "passive"))
    (pad "2" smd rect (at -2.975 4.955 90) (size 1.45 4.191) (layers "F.Cu" "F.Paste" "F.Mask")
      (net 2 "GND") (pinfunction "2") (pintype "passive"))
    (pad "2" smd rect (at -2.975 4.955 90) (size 1.45 4.191) (layers "B.Cu" "B.Paste" "B.Mask")
      (net 2 "GND") (pinfunction "2") (pintype "passive"))
    (pad "2" smd rect (at 2.975 4.955 90) (size 1.45 4.191) (layers "B.Cu" "B.Paste" "B.Mask")
      (net 2 "GND") (pinfunction "2") (pintype "passive"))
  )

  (footprint "si-simulation-test-board-footprints:RF_SMA_BoardEdge_RF2-143-T-17-50-G" (layer "F.Cu")
    (tedit 64FEFFC5)
    (at 91.37 147.614499 90)
    (descr "RF SMA SMD board edge connector")
    (property "Author" "Antmicro")
    (property "License" "Apache-2.0")
    (property "MPN" "RF2-143-T-17-50-G")
    (property "Manufacturer" "ADAM TECH")
    (property "Sheetfile" "si-simulation-test-board.kicad_sch")
    (property "Sheetname" "")
    (attr smd)
    (fp_text reference "J16" (at -4.5 6.88 180) (layer "F.SilkS")
      (effects (font (size 0.7 0.7) (thickness 0.15)) (justify left bottom))
    )
    (fp_text value "Conn_SMA_RF2-143-T-17-50-G" (at 0 9.24 90) (layer "F.Fab")
      (effects (font (size 0.7 0.7) (thickness 0.15)) (justify left bottom))
    )
    (fp_text user "License: Apache-2.0" (at -4.5 12.44 90) (layer "F.Fab") hide
      (effects (font (size 0.7 0.7) (thickness 0.15)) (justify left bottom))
    )
    (fp_text user "Author: Antmicro" (at -4.5 11.24 90) (layer "F.Fab") hide
      (effects (font (size 0.7 0.7) (thickness 0.15)) (justify left bottom))
    )
    (fp_text user "${REFERENCE}" (at -4.5 13.64 90) (layer "F.Fab") hide
      (effects (font (size 0.7 0.7) (thickness 0.15)) (justify left bottom))
    )
    (fp_rect (start -3.995 -7.53) (end 3.995 7.53) (layer "B.CrtYd") (width 0.05) (fill none))
    (fp_rect (start -3.995 -7.53) (end 3.995 7.53) (layer "F.CrtYd") (width 0.05) (fill none))
    (fp_line (start 3.174 2.654) (end -3.15 2.654) (layer "F.Fab") (width 0.15))
    (fp_line (start -3.174 6.455) (end -3.174 1.504) (layer "F.Fab") (width 0.15))
    (fp_line (start -2.65 -6.375) (end -2.65 1.504) (layer "F.Fab") (width 0.15))
    (fp_line (start 3.174 6.455) (end 3.174 1.504) (layer "F.Fab") (width 0.15))
    (fp_line (start 0.38 2.654) (end 0.375 6.455) (layer "F.Fab") (width 0.15))
    (fp_line (start 3.174 6.455) (end 2.375 6.455) (layer "F.Fab") (width 0.15))
    (fp_line (start 2.65 -6.375) (end 2.65 1.504) (layer "F.Fab") (width 0.15))
    (fp_line (start 2.65 -6.375) (end -2.65 -6.375) (layer "F.Fab") (width 0.15))
    (fp_line (start -0.38 2.654) (end -0.38 6.455) (layer "F.Fab") (width 0.15))
    (fp_line (start 2.375 6.455) (end 2.375 2.678) (layer "F.Fab") (width 0.15))
    (fp_line (start 3.174 1.504) (end -3.174 1.504) (layer "F.Fab") (width 0.15))
    (fp_line (start 0.375 6.455) (end -0.38 6.455) (layer "F.Fab") (width 0.15))
    (fp_line (start -2.375 2.678) (end -2.375 6.455) (layer "F.Fab") (width 0.15))
    (fp_line (start -2.375 6.455) (end -3.174 6.455) (layer "F.Fab") (width 0.15))
    (pad "1" smd rect (at 0.007 4.955 90) (size 2.29 4.191) (layers "F.Cu" "F.Paste" "F.Mask")
      (net 10 "Net-(J16-Pad1)") (pinfunction "1") (pintype "passive"))
    (pad "2" smd rect (at -2.975 4.955 90) (size 1.45 4.191) (layers "F.Cu" "F.Paste" "F.Mask")
      (net 2 "GND") (pinfunction "2") (pintype "passive"))
    (pad "2" smd rect (at 2.975 4.955 90) (size 1.45 4.191) (layers "B.Cu" "B.Paste" "B.Mask")
      (net 2 "GND") (pinfunction "2") (pintype "passive"))
    (pad "2" smd rect (at -2.975 4.955 90) (size 1.45 4.191) (layers "B.Cu" "B.Paste" "B.Mask")
      (net 2 "GND") (pinfunction "2") (pintype "passive"))
    (pad "2" smd rect (at 2.975 4.955 90) (size 1.45 4.191) (layers "F.Cu" "F.Paste" "F.Mask")
      (net 2 "GND") (pinfunction "2") (pintype "passive"))
  )

  (footprint "si-simulation-test-board-footprints:RF_SMA_BoardEdge_RF2-143-T-17-50-G" (layer "F.Cu")
    (tedit 64FEFFC5)
    (at 91.32 65.999499 90)
    (descr "RF SMA SMD board edge connector")
    (property "Author" "Antmicro")
    (property "License" "Apache-2.0")
    (property "MPN" "RF2-143-T-17-50-G")
    (property "Manufacturer" "ADAM TECH")
    (property "Sheetfile" "si-simulation-test-board.kicad_sch")
    (property "Sheetname" "")
    (attr smd)
    (fp_text reference "J4" (at -4.5 6.88 180) (layer "F.SilkS")
      (effects (font (size 0.7 0.7) (thickness 0.15)) (justify left bottom))
    )
    (fp_text value "Conn_SMA_RF2-143-T-17-50-G" (at 0 9.24 90) (layer "F.Fab")
      (effects (font (size 0.7 0.7) (thickness 0.15)) (justify left bottom))
    )
    (fp_text user "Author: Antmicro" (at -4.5 11.24 90) (layer "F.Fab") hide
      (effects (font (size 0.7 0.7) (thickness 0.15)) (justify left bottom))
    )
    (fp_text user "${REFERENCE}" (at -4.5 13.64 90) (layer "F.Fab") hide
      (effects (font (size 0.7 0.7) (thickness 0.15)) (justify left bottom))
    )
    (fp_text user "License: Apache-2.0" (at -4.5 12.44 90) (layer "F.Fab") hide
      (effects (font (size 0.7 0.7) (thickness 0.15)) (justify left bottom))
    )
    (fp_rect (start -3.995 -7.53) (end 3.995 7.53) (layer "B.CrtYd") (width 0.05) (fill none))
    (fp_rect (start -3.995 -7.53) (end 3.995 7.53) (layer "F.CrtYd") (width 0.05) (fill none))
    (fp_line (start -2.65 -6.375) (end -2.65 1.504) (layer "F.Fab") (width 0.15))
    (fp_line (start 3.174 1.504) (end -3.174 1.504) (layer "F.Fab") (width 0.15))
    (fp_line (start 2.65 -6.375) (end -2.65 -6.375) (layer "F.Fab") (width 0.15))
    (fp_line (start -2.375 6.455) (end -3.174 6.455) (layer "F.Fab") (width 0.15))
    (fp_line (start 3.174 2.654) (end -3.15 2.654) (layer "F.Fab") (width 0.15))
    (fp_line (start -2.375 2.678) (end -2.375 6.455) (layer "F.Fab") (width 0.15))
    (fp_line (start 2.65 -6.375) (end 2.65 1.504) (layer "F.Fab") (width 0.15))
    (fp_line (start 2.375 6.455) (end 2.375 2.678) (layer "F.Fab") (width 0.15))
    (fp_line (start -3.174 6.455) (end -3.174 1.504) (layer "F.Fab") (width 0.15))
    (fp_line (start 3.174 6.455) (end 2.375 6.455) (layer "F.Fab") (width 0.15))
    (fp_line (start 0.38 2.654) (end 0.375 6.455) (layer "F.Fab") (width 0.15))
    (fp_line (start 3.174 6.455) (end 3.174 1.504) (layer "F.Fab") (width 0.15))
    (fp_line (start 0.375 6.455) (end -0.38 6.455) (layer "F.Fab") (width 0.15))
    (fp_line (start -0.38 2.654) (end -0.38 6.455) (layer "F.Fab") (width 0.15))
    (pad "1" smd rect (at 0.007 4.955 90) (size 2.29 4.191) (layers "F.Cu" "F.Paste" "F.Mask")
      (net 2 "GND") (pinfunction "1") (pintype "passive"))
    (pad "2" smd rect (at 2.975 4.955 90) (size 1.45 4.191) (layers "F.Cu" "F.Paste" "F.Mask")
      (net 2 "GND") (pinfunction "2") (pintype "passive"))
    (pad "2" smd rect (at 2.975 4.955 90) (size 1.45 4.191) (layers "B.Cu" "B.Paste" "B.Mask")
      (net 2 "GND") (pinfunction "2") (pintype "passive"))
    (pad "2" smd rect (at -2.975 4.955 90) (size 1.45 4.191) (layers "F.Cu" "F.Paste" "F.Mask")
      (net 2 "GND") (pinfunction "2") (pintype "passive"))
    (pad "2" smd rect (at -2.975 4.955 90) (size 1.45 4.191) (layers "B.Cu" "B.Paste" "B.Mask")
      (net 2 "GND") (pinfunction "2") (pintype "passive"))
  )

  (footprint "si-simulation-test-board-footprints:RF_SMA_BoardEdge_RF2-143-T-17-50-G" (layer "F.Cu")
    (tedit 64FEFFC5)
    (at 114.0005 49.22)
    (descr "RF SMA SMD board edge connector")
    (property "Author" "Antmicro")
    (property "License" "Apache-2.0")
    (property "MPN" "RF2-143-T-17-50-G")
    (property "Manufacturer" "ADAM TECH")
    (property "Sheetfile" "si-simulation-test-board.kicad_sch")
    (property "Sheetname" "")
    (attr smd)
    (fp_text reference "J21" (at -4.5 6.88 90) (layer "F.SilkS")
      (effects (font (size 0.7 0.7) (thickness 0.15)) (justify left bottom))
    )
    (fp_text value "Conn_SMA_RF2-143-T-17-50-G" (at 0 9.24) (layer "F.Fab")
      (effects (font (size 0.7 0.7) (thickness 0.15)) (justify left bottom))
    )
    (fp_text user "${REFERENCE}" (at -4.5 13.64) (layer "F.Fab") hide
      (effects (font (size 0.7 0.7) (thickness 0.15)) (justify left bottom))
    )
    (fp_text user "License: Apache-2.0" (at -4.5 12.44) (layer "F.Fab") hide
      (effects (font (size 0.7 0.7) (thickness 0.15)) (justify left bottom))
    )
    (fp_text user "Author: Antmicro" (at -4.5 11.24) (layer "F.Fab") hide
      (effects (font (size 0.7 0.7) (thickness 0.15)) (justify left bottom))
    )
    (fp_rect (start -3.995 -7.53) (end 3.995 7.53) (layer "B.CrtYd") (width 0.05) (fill none))
    (fp_rect (start -3.995 -7.53) (end 3.995 7.53) (layer "F.CrtYd") (width 0.05) (fill none))
    (fp_line (start 0.38 2.654) (end 0.375 6.455) (layer "F.Fab") (width 0.15))
    (fp_line (start 3.174 2.654) (end -3.15 2.654) (layer "F.Fab") (width 0.15))
    (fp_line (start 3.174 1.504) (end -3.174 1.504) (layer "F.Fab") (width 0.15))
    (fp_line (start 2.65 -6.375) (end -2.65 -6.375) (layer "F.Fab") (width 0.15))
    (fp_line (start 0.375 6.455) (end -0.38 6.455) (layer "F.Fab") (width 0.15))
    (fp_line (start -0.38 2.654) (end -0.38 6.455) (layer "F.Fab") (width 0.15))
    (fp_line (start -2.375 6.455) (end -3.174 6.455) (layer "F.Fab") (width 0.15))
    (fp_line (start -3.174 6.455) (end -3.174 1.504) (layer "F.Fab") (width 0.15))
    (fp_line (start -2.65 -6.375) (end -2.65 1.504) (layer "F.Fab") (width 0.15))
    (fp_line (start 2.375 6.455) (end 2.375 2.678) (layer "F.Fab") (width 0.15))
    (fp_line (start -2.375 2.678) (end -2.375 6.455) (layer "F.Fab") (width 0.15))
    (fp_line (start 2.65 -6.375) (end 2.65 1.504) (layer "F.Fab") (width 0.15))
    (fp_line (start 3.174 6.455) (end 3.174 1.504) (layer "F.Fab") (width 0.15))
    (fp_line (start 3.174 6.455) (end 2.375 6.455) (layer "F.Fab") (width 0.15))
    (pad "1" smd rect (at 0.007 4.955) (size 2.29 4.191) (layers "F.Cu" "F.Paste" "F.Mask")
      (net 12 "unconnected-(J21-Pad1)") (pinfunction "1") (pintype "passive+no_connect"))
    (pad "2" smd rect (at 2.975 4.955) (size 1.45 4.191) (layers "B.Cu" "B.Paste" "B.Mask")
      (net 2 "GND") (pinfunction "2") (pintype "passive"))
    (pad "2" smd rect (at -2.975 4.955) (size 1.45 4.191) (layers "F.Cu" "F.Paste" "F.Mask")
      (net 2 "GND") (pinfunction "2") (pintype "passive"))
    (pad "2" smd rect (at 2.975 4.955) (size 1.45 4.191) (layers "F.Cu" "F.Paste" "F.Mask")
      (net 2 "GND") (pinfunction "2") (pintype "passive"))
    (pad "2" smd rect (at -2.975 4.955) (size 1.45 4.191) (layers "B.Cu" "B.Paste" "B.Mask")
      (net 2 "GND") (pinfunction "2") (pintype "passive"))
  )

  (footprint "si-simulation-test-board-footprints:RF_SMA_BoardEdge_RF2-143-T-17-50-G" (layer "F.Cu")
    (tedit 64FEFFC5)
    (at 124.0505 49.27)
    (descr "RF SMA SMD board edge connector")
    (property "Author" "Antmicro")
    (property "License" "Apache-2.0")
    (property "MPN" "RF2-143-T-17-50-G")
    (property "Manufacturer" "ADAM TECH")
    (property "Sheetfile" "si-simulation-test-board.kicad_sch")
    (property "Sheetname" "")
    (attr smd)
    (fp_text reference "J22" (at -4.5 6.88 90) (layer "F.SilkS")
      (effects (font (size 0.7 0.7) (thickness 0.15)) (justify left bottom))
    )
    (fp_text value "Conn_SMA_RF2-143-T-17-50-G" (at 0 9.24) (layer "F.Fab")
      (effects (font (size 0.7 0.7) (thickness 0.15)) (justify left bottom))
    )
    (fp_text user "Author: Antmicro" (at -4.5 11.24) (layer "F.Fab") hide
      (effects (font (size 0.7 0.7) (thickness 0.15)) (justify left bottom))
    )
    (fp_text user "License: Apache-2.0" (at -4.5 12.44) (layer "F.Fab") hide
      (effects (font (size 0.7 0.7) (thickness 0.15)) (justify left bottom))
    )
    (fp_text user "${REFERENCE}" (at -4.5 13.64) (layer "F.Fab") hide
      (effects (font (size 0.7 0.7) (thickness 0.15)) (justify left bottom))
    )
    (fp_rect (start -3.995 -7.53) (end 3.995 7.53) (layer "B.CrtYd") (width 0.05) (fill none))
    (fp_rect (start -3.995 -7.53) (end 3.995 7.53) (layer "F.CrtYd") (width 0.05) (fill none))
    (fp_line (start -2.375 2.678) (end -2.375 6.455) (layer "F.Fab") (width 0.15))
    (fp_line (start -2.375 6.455) (end -3.174 6.455) (layer "F.Fab") (width 0.15))
    (fp_line (start 0.375 6.455) (end -0.38 6.455) (layer "F.Fab") (width 0.15))
    (fp_line (start -2.65 -6.375) (end -2.65 1.504) (layer "F.Fab") (width 0.15))
    (fp_line (start 3.174 2.654) (end -3.15 2.654) (layer "F.Fab") (width 0.15))
    (fp_line (start -3.174 6.455) (end -3.174 1.504) (layer "F.Fab") (width 0.15))
    (fp_line (start 3.174 6.455) (end 2.375 6.455) (layer "F.Fab") (width 0.15))
    (fp_line (start 0.38 2.654) (end 0.375 6.455) (layer "F.Fab") (width 0.15))
    (fp_line (start 2.375 6.455) (end 2.375 2.678) (layer "F.Fab") (width 0.15))
    (fp_line (start -0.38 2.654) (end -0.38 6.455) (layer "F.Fab") (width 0.15))
    (fp_line (start 3.174 6.455) (end 3.174 1.504) (layer "F.Fab") (width 0.15))
    (fp_line (start 2.65 -6.375) (end 2.65 1.504) (layer "F.Fab") (width 0.15))
    (fp_line (start 3.174 1.504) (end -3.174 1.504) (layer "F.Fab") (width 0.15))
    (fp_line (start 2.65 -6.375) (end -2.65 -6.375) (layer "F.Fab") (width 0.15))
    (pad "1" smd rect (at 0.007 4.955) (size 2.29 4.191) (layers "F.Cu" "F.Paste" "F.Mask")
      (net 13 "unconnected-(J22-Pad1)") (pinfunction "1") (pintype "passive+no_connect"))
    (pad "2" smd rect (at -2.975 4.955) (size 1.45 4.191) (layers "B.Cu" "B.Paste" "B.Mask")
      (net 2 "GND") (pinfunction "2") (pintype "passive"))
    (pad "2" smd rect (at 2.975 4.955) (size 1.45 4.191) (layers "F.Cu" "F.Paste" "F.Mask")
      (net 2 "GND") (pinfunction "2") (pintype "passive"))
    (pad "2" smd rect (at 2.975 4.955) (size 1.45 4.191) (layers "B.Cu" "B.Paste" "B.Mask")
      (net 2 "GND") (pinfunction "2") (pintype "passive"))
    (pad "2" smd rect (at -2.975 4.955) (size 1.45 4.191) (layers "F.Cu" "F.Paste" "F.Mask")
      (net 2 "GND") (pinfunction "2") (pintype "passive"))
  )

  (footprint "si-simulation-test-board-footprints:RF_SMA_BoardEdge_RF2-143-T-17-50-G" (layer "F.Cu")
    (tedit 64FEFFC5)
    (at 91.37 85.999499 90)
    (descr "RF SMA SMD board edge connector")
    (property "Author" "Antmicro")
    (property "License" "Apache-2.0")
    (property "MPN" "RF2-143-T-17-50-G")
    (property "Manufacturer" "ADAM TECH")
    (property "Sheetfile" "si-simulation-test-board.kicad_sch")
    (property "Sheetname" "")
    (attr smd)
    (fp_text reference "J7" (at -4.5 6.88 180) (layer "F.SilkS")
      (effects (font (size 0.7 0.7) (thickness 0.15)) (justify left bottom))
    )
    (fp_text value "Conn_SMA_RF2-143-T-17-50-G" (at 0 9.24 90) (layer "F.Fab")
      (effects (font (size 0.7 0.7) (thickness 0.15)) (justify left bottom))
    )
    (fp_text user "License: Apache-2.0" (at -4.5 12.44 90) (layer "F.Fab") hide
      (effects (font (size 0.7 0.7) (thickness 0.15)) (justify left bottom))
    )
    (fp_text user "Author: Antmicro" (at -4.5 11.24 90) (layer "F.Fab") hide
      (effects (font (size 0.7 0.7) (thickness 0.15)) (justify left bottom))
    )
    (fp_text user "${REFERENCE}" (at -4.5 13.64 90) (layer "F.Fab") hide
      (effects (font (size 0.7 0.7) (thickness 0.15)) (justify left bottom))
    )
    (fp_rect (start -3.995 -7.53) (end 3.995 7.53) (layer "B.CrtYd") (width 0.05) (fill none))
    (fp_rect (start -3.995 -7.53) (end 3.995 7.53) (layer "F.CrtYd") (width 0.05) (fill none))
    (fp_line (start 3.174 6.455) (end 2.375 6.455) (layer "F.Fab") (width 0.15))
    (fp_line (start 2.65 -6.375) (end 2.65 1.504) (layer "F.Fab") (width 0.15))
    (fp_line (start 3.174 2.654) (end -3.15 2.654) (layer "F.Fab") (width 0.15))
    (fp_line (start -2.375 6.455) (end -3.174 6.455) (layer "F.Fab") (width 0.15))
    (fp_line (start -3.174 6.455) (end -3.174 1.504) (layer "F.Fab") (width 0.15))
    (fp_line (start -2.375 2.678) (end -2.375 6.455) (layer "F.Fab") (width 0.15))
    (fp_line (start 2.65 -6.375) (end -2.65 -6.375) (layer "F.Fab") (width 0.15))
    (fp_line (start 3.174 1.504) (end -3.174 1.504) (layer "F.Fab") (width 0.15))
    (fp_line (start -0.38 2.654) (end -0.38 6.455) (layer "F.Fab") (width 0.15))
    (fp_line (start 2.375 6.455) (end 2.375 2.678) (layer "F.Fab") (width 0.15))
    (fp_line (start 0.375 6.455) (end -0.38 6.455) (layer "F.Fab") (width 0.15))
    (fp_line (start 0.38 2.654) (end 0.375 6.455) (layer "F.Fab") (width 0.15))
    (fp_line (start 3.174 6.455) (end 3.174 1.504) (layer "F.Fab") (width 0.15))
    (fp_line (start -2.65 -6.375) (end -2.65 1.504) (layer "F.Fab") (width 0.15))
    (pad "1" smd rect (at 0.007 4.955 90) (size 2.29 4.191) (layers "F.Cu" "F.Paste" "F.Mask")
      (net 5 "Net-(J7-Pad1)") (pinfunction "1") (pintype "passive"))
    (pad "2" smd rect (at -2.975 4.955 90) (size 1.45 4.191) (layers "B.Cu" "B.Paste" "B.Mask")
      (net 2 "GND") (pinfunction "2") (pintype "passive"))
    (pad "2" smd rect (at 2.975 4.955 90) (size 1.45 4.191) (layers "B.Cu" "B.Paste" "B.Mask")
      (net 2 "GND") (pinfunction "2") (pintype "passive"))
    (pad "2" smd rect (at -2.975 4.955 90) (size 1.45 4.191) (layers "F.Cu" "F.Paste" "F.Mask")
      (net 2 "GND") (pinfunction "2") (pintype "passive"))
    (pad "2" smd rect (at 2.975 4.955 90) (size 1.45 4.191) (layers "F.Cu" "F.Paste" "F.Mask")
      (net 2 "GND") (pinfunction "2") (pintype "passive"))
  )

  (footprint "si-simulation-test-board-footprints:R_0201" (layer "F.Cu")
    (tedit 5FBD1D44)
    (at 128.744001 88.992501 180)
    (descr "Resistor SMD 0201")
    (tags "resistor SMD 0201")
    (property "Author" "Antmicro")
    (property "DNP" "DNP")
    (property "License" "Apache-2.0")
    (property "MPN" "CR0201-FX-0R00GLF")
    (property "Manufacturer" "Bourns")
    (property "Sheetfile" "si-simulation-test-board.kicad_sch")
    (property "Sheetname" "")
    (property "Tolerance" "1%")
    (property "Val" "0R")
    (attr smd)
    (fp_text reference "R3" (at 0 -0.5) (layer "F.SilkS") hide
      (effects (font (size 0.7 0.7) (thickness 0.15)) (justify right bottom))
    )
    (fp_text value "R_0R_0201" (at 0 1.25) (layer "F.Fab")
      (effects (font (size 0.7 0.7) (thickness 0.15)) (justify right bottom))
    )
    (fp_text user "Author: Antmicro" (at -0.71 5.25) (layer "F.Fab") hide
      (effects (font (size 0.7 0.7) (thickness 0.15)) (justify right bottom))
    )
    (fp_text user "License: Apache-2.0" (at -0.71 4.25) (layer "F.Fab") hide
      (effects (font (size 0.7 0.7) (thickness 0.15)) (justify right bottom))
    )
    (fp_text user "${REFERENCE}" (at -0.71 3.25) (layer "F.Fab") hide
      (effects (font (size 0.7 0.7) (thickness 0.15)) (justify right bottom))
    )
    (fp_rect (start -0.71 -0.36) (end 0.71 0.36) (layer "F.CrtYd") (width 0.05) (fill none))
    (fp_rect (start -0.3 -0.15) (end 0.298 0.148) (layer "F.Fab") (width 0.15) (fill none))
    (pad "" smd roundrect (at 0.344 0 180) (size 0.318 0.36) (layers "F.Paste") (roundrect_rratio 0.25))
    (pad "" smd roundrect (at -0.346 0 180) (size 0.318 0.36) (layers "F.Paste") (roundrect_rratio 0.25))
    (pad "1" smd roundrect (at -0.32 0 180) (size 0.46 0.4) (layers "F.Cu" "F.Mask") (roundrect_rratio 0.25)
      (net 2 "GND") (pintype "passive"))
    (pad "2" smd roundrect (at 0.32 0 180) (size 0.46 0.4) (layers "F.Cu" "F.Mask") (roundrect_rratio 0.25)
      (net 5 "Net-(J7-Pad1)") (pintype "passive"))
  )
  (gr_rect (start 94 52) (end 144 152) (layer "Edge.Cuts") (width 0.1) (fill none))

  (segment (start 141.6625 75.9925) (end 141.675 75.98) (width 0.185) (layer "F.Cu") (net 1))
  (segment (start 96.275 75.9925) (end 141.6625 75.9925) (width 0.185) (layer "F.Cu") (net 1))
  (segment (start 111.906 146.415) (end 111.52 146.415) (width 0.185) (layer "F.Cu") (net 2))
  (segment (start 100.95 65.9925) (end 96.275 65.9925) (width 0.185) (layer "F.Cu") (net 2))
  (segment (start 111.52 146.415) (end 111.51 146.405) (width 0.185) (layer "F.Cu") (net 2))
  (via (at 116.576043 99.109757) (size 0.55) (drill 0.2) (layers "F.Cu" "B.Cu") (net 2))
  (via (at 138.775 78.975) (size 0.55) (drill 0.2) (layers "F.Cu" "B.Cu") (free) (net 2))
  (via (at 94.5 53.075) (size 0.55) (drill 0.2) (layers "F.Cu" "B.Cu") (free) (net 2))
  (via (at 96.325 103.025) (size 0.55) (drill 0.2) (layers "F.Cu" "B.Cu") (free) (net 2))
  (via (at 132.349 100.272) (size 0.55) (drill 0.2) (layers "F.Cu" "B.Cu") (free) (net 2))
  (via (at 98.1 130.59) (size 0.55) (drill 0.2) (layers "F.Cu" "B.Cu") (free) (net 2))
  (via (at 140.2 114.35) (size 0.55) (drill 0.2) (layers "F.Cu" "B.Cu") (free) (net 2))
  (via (at 121.96 117.215) (size 0.55) (drill 0.2) (layers "F.Cu" "B.Cu") (free) (net 2))
  (via (at 128.899 103.622) (size 0.55) (drill 0.2) (layers "F.Cu" "B.Cu") (free) (net 2))
  (via (at 108 117.815) (size 0.55) (drill 0.2) (layers "F.Cu" "B.Cu") (free) (net 2))
  (via (at 110.7 133.815) (size 0.55) (drill 0.2) (layers "F.Cu" "B.Cu") (free) (net 2))
  (via (at 100.44 133.815) (size 0.55) (drill 0.2) (layers "F.Cu" "B.Cu") (free) (net 2))
  (via (at 130.793898 118.608898) (size 0.55) (drill 0.2) (layers "F.Cu" "B.Cu") (free) (net 2))
  (via (at 141.725 99.025) (size 0.55) (drill 0.2) (layers "F.Cu" "B.Cu") (free) (net 2))
  (via (at 105.04 133.815) (size 0.55) (drill 0.2) (layers "F.Cu" "B.Cu") (free) (net 2))
  (via (at 125.549 100.272) (size 0.55) (drill 0.2) (layers "F.Cu" "B.Cu") (free) (net 2))
  (via (at 126.56 117.215) (size 0.55) (drill 0.2) (layers "F.Cu" "B.Cu") (free) (net 2))
  (via (at 94.499999 78.975) (size 0.55) (drill 0.2) (layers "F.Cu" "B.Cu") (free) (net 2))
  (via (at 125.245 130.915) (size 0.55) (drill 0.2) (layers "F.Cu" "B.Cu") (free) (net 2))
  (via (at 126.599 103.622) (size 0.55) (drill 0.2) (layers "F.Cu" "B.Cu") (free) (net 2))
  (via (at 138.1 123.487935) (size 0.55) (drill 0.2) (layers "F.Cu" "B.Cu") (free) (net 2))
  (via (at 94.8 83) (size 0.55) (drill 0.2) (layers "F.Cu" "B.Cu") (free) (net 2))
  (via (at 111.025 54.075) (size 0.55) (drill 0.2) (layers "F.Cu" "B.Cu") (free) (net 2))
  (via (at 94.8 114.343973) (size 0.55) (drill 0.2) (layers "F.Cu" "B.Cu") (free) (net 2))
  (via (at 120.629 100.212) (size 0.55) (drill 0.2) (layers "F.Cu" "B.Cu") (free) (net 2))
  (via (at 96.325 124.64) (size 0.55) (drill 0.2) (layers "F.Cu" "B.Cu") (free) (net 2))
  (via (at 98.1 83.025) (size 0.55) (drill 0.2) (layers "F.Cu" "B.Cu") (free) (net 2))
  (via (at 126.6075 138.415) (size 0.55) (drill 0.2) (layers "F.Cu" "B.Cu") (free) (net 2))
  (via (at 96.325 83.025) (size 0.55) (drill 0.2) (layers "F.Cu" "B.Cu") (free) (net 2))
  (via (at 112.4075 136.815) (size 0.55) (drill 0.2) (layers "F.Cu" "B.Cu") (free) (net 2))
  (via (at 113.2 146.415) (size 0.55) (drill 0.2) (layers "F.Cu" "B.Cu") (net 2))
  (via (at 105.553411 120.261589) (size 0.55) (drill 0.2) (layers "F.Cu" "B.Cu") (free) (net 2))
  (via (at 131.199 103.622) (size 0.55) (drill 0.2) (layers "F.Cu" "B.Cu") (free) (net 2))
  (via (at 140.2 103) (size 0.55) (drill 0.2) (layers "F.Cu" "B.Cu") (free) (net 2))
  (via (at 104.747309 121.067691) (size 0.55) (drill 0.2) (layers "F.Cu" "B.Cu") (free) (net 2))
  (via (at 118.5 117.215) (size 0.55) (drill 0.2) (layers "F.Cu" "B.Cu") (free) (net 2))
  (via (at 143.5 120.275) (size 0.55) (drill 0.2) (layers "F.Cu" "B.Cu") (free) (net 2))
  (via (at 127.6 117.215) (size 0.55) (drill 0.2) (layers "F.Cu" "B.Cu") (free) (net 2))
  (via (at 94.8 88.95) (size 0.55) (drill 0.2) (layers "F.Cu" "B.Cu") (free) (net 2))
  (via (at 143.4 134.615) (size 0.55) (drill 0.2) (layers "F.Cu" "B.Cu") (free) (net 2))
  (via (at 140.1 140.49) (size 0.55) (drill 0.2) (layers "F.Cu" "B.Cu") (free) (net 2))
  (via (at 133.226346 121.041346) (size 0.55) (drill 0.2) (layers "F.Cu" "B.Cu") (free) (net 2))
  (via (at 94.5 68.975) (size 0.55) (drill 0.2) (layers "F.Cu" "B.Cu") (free) (net 2))
  (via (at 137.15 57.08) (size 0.55) (drill 0.2) (layers "F.Cu" "B.Cu") (free) (net 2))
  (via (at 141.675 63.025) (size 0.55) (drill 0.2) (layers "F.Cu" "B.Cu") (free) (net 2))
  (via (at 135.8 133.815) (size 0.55) (drill 0.2) (layers "F.Cu" "B.Cu") (free) (net 2))
  (via (at 96.325 140.59) (size 0.55) (drill 0.2) (layers "F.Cu" "B.Cu") (free) (net 2))
  (via (at 118.64 133.815) (size 0.55) (drill 0.2) (layers "F.Cu" "B.Cu") (free) (net 2))
  (via (at 126.7 133.815) (size 0.55) (drill 0.2) (layers "F.Cu" "B.Cu") (free) (net 2))
  (via (at 124.4 133.815) (size 0.55) (drill 0.2) (layers "F.Cu" "B.Cu") (free) (net 2))
  (via (at 96.275 73.025001) (size 0.55) (drill 0.2) (layers "F.Cu" "B.Cu") (free) (net 2))
  (via (at 115.3 133.815) (size 0.55) (drill 0.2) (layers "F.Cu" "B.Cu") (free) (net 2))
  (via (at 94.5 73.025) (size 0.55) (drill 0.2) (layers "F.Cu" "B.Cu") (free) (net 2))
  (via (at 141.725 114.375) (size 0.55) (drill 0.2) (layers "F.Cu" "B.Cu") (free) (net 2))
  (via (at 98.1 150.59) (size 0.55) (drill 0.2) (layers "F.Cu" "B.Cu") (free) (net 2))
  (via (at 129.973654 117.788654) (size 0.55) (drill 0.2) (layers "F.Cu" "B.Cu") (free) (net 2))
  (via (at 134.64 133.815) (size 0.55) (drill 0.2) (layers "F.Cu" "B.Cu") (free) (net 2))
  (via (at 141.825 130.515) (size 0.55) (drill 0.2) (layers "F.Cu" "B.Cu") (free) (net 2))
  (via (at 140.275 150.59) (size 0.55) (drill 0.2) (layers "F.Cu" "B.Cu") (free) (net 2))
  (via (at 143.5 99.025) (size 0.55) (drill 0.2) (layers "F.Cu" "B.Cu") (free) (net 2))
  (via (at 115.16 117.215) (size 0.55) (drill 0.2) (layers "F.Cu" "B.Cu") (free) (net 2))
  (via (at 96.325 120.318973) (size 0.55) (drill 0.2) (layers "F.Cu" "B.Cu") (free) (net 2))
  (via (at 141.725 88.925) (size 0.55) (drill 0.2) (layers "F.Cu" "B.Cu") (free) (net 2))
  (via (at 139.9 58.975) (size 0.55) (drill 0.2) (layers "F.Cu" "B.Cu") (free) (net 2))
  (via (at 111.51 146.405) (size 0.55) (drill 0.2) (layers "F.Cu" "B.Cu") (net 2))
  (via (at 103.9 133.815) (size 0.55) (drill 0.2) (layers "F.Cu" "B.Cu") (free) (net 2))
  (via (at 111.05 52.55) (size 0.55) (drill 0.2) (layers "F.Cu" "B.Cu") (free) (net 2))
  (via (at 94.8 150.565) (size 0.55) (drill 0.2) (layers "F.Cu" "B.Cu") (free) (net 2))
  (via (at 96.325 98.975) (size 0.55) (drill 0.2) (layers "F.Cu" "B.Cu") (free) (net 2))
  (via (at 132.420244 120.235244) (size 0.55) (drill 0.2) (layers "F.Cu" "B.Cu") (free) (net 2))
  (via (at 98.1 144.64) (size 0.55) (drill 0.2) (layers "F.Cu" "B.Cu") (free) (net 2))
  (via (at 119.66 117.215) (size 0.55) (drill 0.2) (layers "F.Cu" "B.Cu") (free) (net 2))
  (via (at 108.5 133.815) (size 0.55) (drill 0.2) (layers "F.Cu" "B.Cu") (free) (net 2))
  (via (at 123.1 117.215) (size 0.55) (drill 0.2) (layers "F.Cu" "B.Cu") (free) (net 2))
  (via (at 98.1 124.64) (size 0.55) (drill 0.2) (layers "F.Cu" "B.Cu") (free) (net 2))
  (via (at 123.24 133.815) (size 0.55) (drill 0.2) (layers "F.Cu" "B.Cu") (free) (net 2))
  (via (at 140.2 108.9) (size 0.55) (drill 0.2) (layers "F.Cu" "B.Cu") (free) (net 2))
  (via (at 94.8 93) (size 0.55) (drill 0.2) (layers "F.Cu" "B.Cu") (free) (net 2))
  (via (at 117.025 55.850001) (size 0.55) (drill 0.2) (layers "F.Cu" "B.Cu") (free) (net 2))
  (via (at 121.05 54.175) (size 0.55) (drill 0.2) (layers "F.Cu" "B.Cu") (free) (net 2))
  (via (at 99.4 133.815) (size 0.55) (drill 0.2) (layers "F.Cu" "B.Cu") (free) (net 2))
  (via (at 141.625 134.615) (size 0.55) (drill 0.2) (layers "F.Cu" "B.Cu") (free) (net 2))
  (via (at 140.2 83) (size 0.55) (drill 0.2) (layers "F.Cu" "B.Cu") (free) (net 2))
  (via (at 133.5 133.815) (size 0.55) (drill 0.2) (layers "F.Cu" "B.Cu") (free) (net 2))
  (via (at 127.749 100.272) (size 0.55) (drill 0.2) (layers "F.Cu" "B.Cu") (free) (net 2))
  (via (at 141.725 83.025) (size 0.55) (drill 0.2) (layers "F.Cu" "B.Cu") (free) (net 2))
  (via (at 101.6 133.815) (size 0.55) (drill 0.2) (layers "F.Cu" "B.Cu") (free) (net 2))
  (via (at 96.325 134.64) (size 0.55) (drill 0.2) (layers "F.Cu" "B.Cu") (free) (net 2))
  (via (at 94.8 108.95) (size 0.55) (drill 0.2) (layers "F.Cu" "B.Cu") (free) (net 2))
  (via (at 143.2 73.05) (size 0.55) (drill 0.2) (layers "F.Cu" "B.Cu") (free) (net 2))
  (via (at 143.2 69) (size 0.55) (drill 0.2) (layers "F.Cu" "B.Cu") (free) (net 2))
  (via (at 102.74 133.815) (size 0.55) (drill 0.2) (layers "F.Cu" "B.Cu") (free) (net 2))
  (via (at 127.075 52.65) (size 0.55) (drill 0.2) (layers "F.Cu" "B.Cu") (free) (net 2))
  (via (at 140.2 92.9) (size 0.55) (drill 0.2) (layers "F.Cu" "B.Cu") (free) (net 2))
  (via (at 103.120963 122.694037) (size 0.55) (drill 0.2) (layers "F.Cu" "B.Cu") (free) (net 2))
  (via (at 126.6075 136.815) (size 0.55) (drill 0.2) (layers "F.Cu" "B.Cu") (free) (net 2))
  (via (at 121.075 52.65) (size 0.55) (drill 0.2) (layers "F.Cu" "B.Cu") (free) (net 2))
  (via (at 110.54 130.915) (size 0.55) (drill 0.2) (layers "F.Cu" "B.Cu") (free) (net 2))
  (via (at 119.8 133.815) (size 0.55) (drill 0.2) (layers "F.Cu" "B.Cu") (free) (net 2))
  (via (at 98.1 134.64) (size 0.55) (drill 0.2) (layers "F.Cu" "B.Cu") (free) (net 2))
  (via (at 136.94 133.815) (size 0.55) (drill 0.2) (layers "F.Cu" "B.Cu") (free) (net 2))
  (via (at 143.5 92.925) (size 0.55) (drill 0.2) (layers "F.Cu" "B.Cu") (free) (net 2))
  (via (at 136.94 123.487935) (size 0.55) (drill 0.2) (layers "F.Cu" "B.Cu") (free) (net 2))
  (via (at 114 117.215) (size 0.55) (drill 0.2) (layers "F.Cu" "B.Cu") (free) (net 2))
  (via (at 107.34 133.815) (size 0.55) (drill 0.2) (layers "F.Cu" "B.Cu") (free) (net 2))
  (via (at 141.675 53.025) (size 0.55) (drill 0.2) (layers "F.Cu" "B.Cu") (free) (net 2))
  (via (at 128.9 133.815) (size 0.55) (drill 0.2) (layers "F.Cu" "B.Cu") (free) (net 2))
  (via (at 125.54 133.815) (size 0.55) (drill 0.2) (layers "F.Cu" "B.Cu") (free) (net 2))
  (via (at 106.2 133.815) (size 0.55) (drill 0.2) (layers "F.Cu" "B.Cu") (free) (net 2))
  (via (at 94.8 103) (size 0.55) (drill 0.2) (layers "F.Cu" "B.Cu") (free) (net 2))
  (via (at 143.5 83.025) (size 0.55) (drill 0.2) (layers "F.Cu" "B.Cu") (free) (net 2))
  (via (at 129.194001 88.992501) (size 0.55) (drill 0.2) (layers "F.Cu" "B.Cu") (net 2))
  (via (at 96.275 63.025) (size 0.55) (drill 0.2) (layers "F.Cu" "B.Cu") (free) (net 2))
  (via (at 98.1 93.025) (size 0.55) (drill 0.2) (layers "F.Cu" "B.Cu") (free) (net 2))
  (via (at 98.1 88.975) (size 0.55) (drill 0.2) (layers "F.Cu" "B.Cu") (free) (net 2))
  (via (at 140.3 130.49) (size 0.55) (drill 0.2) (layers "F.Cu" "B.Cu") (free) (net 2))
  (via (at 116.44 133.815) (size 0.55) (drill 0.2) (layers "F.Cu" "B.Cu") (free) (net 2))
  (via (at 141.675 58.975) (size 0.55) (drill 0.2) (layers "F.Cu" "B.Cu") (free) (net 2))
  (via (at 141.625 140.515) (size 0.55) (drill 0.2) (layers "F.Cu" "B.Cu") (free) (net 2))
  (via (at 94.8 120.293973) (size 0.55) (drill 0.2) (layers "F.Cu" "B.Cu") (free) (net 2))
  (via (at 97.8 63.05) (size 0.55) (drill 0.2) (layers "F.Cu" "B.Cu") (free) (net 2))
  (via (at 143.5 144.515) (size 0.55) (drill 0.2) (layers "F.Cu" "B.Cu") (free) (net 2))
  (via (at 100.95 65.9925) (size 0.55) (drill 0.2) (layers "F.Cu" "B.Cu") (net 2))
  (via (at 141.725 144.515) (size 0.55) (drill 0.2) (layers "F.Cu" "B.Cu") (free) (net 2))
  (via (at 143.5 88.925) (size 0.55) (drill 0.2) (layers "F.Cu" "B.Cu") (free) (net 2))
  (via (at 140.2 120.25) (size 0.55) (drill 0.2) (layers "F.Cu" "B.Cu") (free) (net 2))
  (via (at 101.935 56.0075) (size 0.55) (drill 0.2) (layers "F.Cu" "B.Cu") (net 2))
  (via (at 117.84 130.915) (size 0.55) (drill 0.2) (layers "F.Cu" "B.Cu") (free) (net 2))
  (via (at 96.325 130.59) (size 0.55) (drill 0.2) (layers "F.Cu" "B.Cu") (free) (net 2))
  (via (at 99.8 123.515) (size 0.55) (drill 0.2) (layers "F.Cu" "B.Cu") (free) (net 2))
  (via (at 98.1 114.368973) (size 0.55) (drill 0.2) (layers "F.Cu" "B.Cu") (free) (net 2))
  (via (at 113.74 120.115) (size 0.55) (drill 0.2) (layers "F.Cu" "B.Cu") (free) (net 2))
  (via (at 143.5 114.375) (size 0.55) (drill 0.2) (layers "F.Cu" "B.Cu") (free) (net 2))
  (via (at 141.725 92.925) (size 0.55) (drill 0.2) (layers "F.Cu" "B.Cu") (free) (net 2))
  (via (at 140.1 134.59) (size 0.55) (drill 0.2) (layers "F.Cu" "B.Cu") (free) (net 2))
  (via (at 141.725 120.275) (size 0.55) (drill 0.2) (layers "F.Cu" "B.Cu") (free) (net 2))
  (via (at 96.275 53.075) (size 0.55) (drill 0.2) (layers "F.Cu" "B.Cu") (free) (net 2))
  (via (at 139.9 132.715) (size 0.55) (drill 0.2) (layers "F.Cu" "B.Cu") (free) (net 2))
  (via (at 143.575 150.615) (size 0.55) (drill 0.2) (layers "F.Cu" "B.Cu") (free) (net 2))
  (via (at 134.046589 121.861589) (size 0.55) (drill 0.2) (layers "F.Cu" "B.Cu") (free) (net 2))
  (via (at 139 123.915) (size 0.55) (drill 0.2) (layers "F.Cu" "B.Cu") (free) (net 2))
  (via (at 122.84 120.115) (size 0.55) (drill 0.2) (layers "F.Cu" "B.Cu") (free) (net 2))
  (via (at 96.275 78.975) (size 0.55) (drill 0.2) (layers "F.Cu" "B.Cu") (free) (net 2))
  (via (at 96.275 59.075) (size 0.55) (drill 0.2) (layers "F.Cu" "B.Cu") (free) (net 2))
  (via (at 143.6 130.515) (size 0.55) (drill 0.2) (layers "F.Cu" "B.Cu") (free) (net 2))
  (via (at 132.381 106.768) (size 0.55) (drill 0.2) (layers "F.Cu" "B.Cu") (free) (net 2))
  (via (at 96.325 150.59) (size 0.55) (drill 0.2) (layers "F.Cu" "B.Cu") (free) (net 2))
  (via (at 117.6 133.815) (size 0.55) (drill 0.2) (layers "F.Cu" "B.Cu") (free) (net 2))
  (via (at 131.2 133.815) (size 0.55) (drill 0.2) (layers "F.Cu" "B.Cu") (free) (net 2))
  (via (at 94.8 134.615) (size 0.55) (drill 0.2) (layers "F.Cu" "B.Cu") (free) (net 2))
  (via (at 140.3 124.59) (size 0.55) (drill 0.2) (layers "F.Cu" "B.Cu") (free) (net 2))
  (via (at 94.499999 59.075) (size 0.55) (drill 0.2) (layers "F.Cu" "B.Cu") (free) (net 2))
  (via (at 140.2 99) (size 0.55) (drill 0.2) (layers "F.Cu" "B.Cu") (free) (net 2))
  (via (at 116.3 117.215) (size 0.55) (drill 0.2) (layers "F.Cu" "B.Cu") (free) (net 2))
  (via (at 127.05 54.175) (size 0.55) (drill 0.2) (layers "F.Cu" "B.Cu") (free) (net 2))
  (via (at 141.725 103.025) (size 0.55) (drill 0.2) (layers "F.Cu" "B.Cu") (free) (net 2))
  (via (at 125.4 117.215) (size 0.55) (drill 0.2) (layers "F.Cu" "B.Cu") (free) (net 2))
  (via (at 139.9 53.025) (size 0.55) (drill 0.2) (layers "F.Cu" "B.Cu") (free) (net 2))
  (via (at 109.54 133.815) (size 0.55) (drill 0.2) (layers "F.Cu" "B.Cu") (free) (net 2))
  (via (at 139.9 63.025) (size 0.55) (drill 0.2) (layers "F.Cu" "B.Cu") (free) (net 2))
  (via (at 131.6 119.415) (size 0.55) (drill 0.2) (layers "F.Cu" "B.Cu") (free) (net 2))
  (via (at 139.9 78.975) (size 0.55) (drill 0.2) (layers "F.Cu" "B.Cu") (free) (net 2))
  (via (at 96.275 68.975) (size 0.55) (drill 0.2) (layers "F.Cu" "B.Cu") (free) (net 2))
  (via (at 122.1 133.815) (size 0.55) (drill 0.2) (layers "F.Cu" "B.Cu") (free) (net 2))
  (via (at 120.616 105.327) (size 0.55) (drill 0.2) (layers "F.Cu" "B.Cu") (free) (net 2))
  (via (at 113 133.815) (size 0.55) (drill 0.2) (layers "F.Cu" "B.Cu") (free) (net 2))
  (via (at 125.945 130.915) (size 0.55) (drill 0.2) (layers "F.Cu" "B.Cu") (free) (net 2))
  (via (at 143.2 63.05) (size 0.55) (drill 0.2) (layers "F.Cu" "B.Cu") (free) (net 2))
  (via (at 94.8 144.615) (size 0.55) (drill 0.2) (layers "F.Cu" "B.Cu") (free) (net 2))
  (via (at 141.675 73.025) (size 0.55) (drill 0.2) (layers "F.Cu" "B.Cu") (free) (net 2))
  (via (at 96.325 144.64) (size 0.55) (drill 0.2) (layers "F.Cu" "B.Cu") (free) (net 2))
  (via (at 97.8 59.1) (size 0.55) (drill 0.2) (layers "F.Cu" "B.Cu") (free) (net 2))
  (via (at 141.825 124.615) (size 0.55) (drill 0.2) (layers "F.Cu" "B.Cu") (free) (net 2))
  (via (at 102.300719 123.514281) (size 0.55) (drill 0.2) (layers "F.Cu" "B.Cu") (free) (net 2))
  (via (at 97.8 69) (size 0.55) (drill 0.2) (layers "F.Cu" "B.Cu") (free) (net 2))
  (via (at 106.373654 119.441346) (size 0.55) (drill 0.2) (layers "F.Cu" "B.Cu") (free) (net 2))
  (via (at 124.26 117.215) (size 0.55) (drill 0.2) (layers "F.Cu" "B.Cu") (free) (net 2))
  (via (at 109.84 130.915) (size 0.55) (drill 0.2) (layers "F.Cu" "B.Cu") (free) (net 2))
  (via (at 112.86 117.215) (size 0.55) (drill 0.2) (layers "F.Cu" "B.Cu") (free) (net 2))
  (via (at 127.38 146.345) (size 0.55) (drill 0.2) (layers "F.Cu" "B.Cu") (net 2))
  (via (at 143.4 140.515) (size 0.55) (drill 0.2) (layers "F.Cu" "B.Cu") (free) (net 2))
  (via (at 117.025 54.075) (size 0.55) (drill 0.2) (layers "F.Cu" "B.Cu") (free) (net 2))
  (via (at 98.1 108.975) (size 0.55) (drill 0.2) (layers "F.Cu" "B.Cu") (free) (net 2))
  (via (at 97.8 53.1) (size 0.55) (drill 0.2) (layers "F.Cu" "B.Cu") (free) (net 2))
  (via (at 98.1 103.025) (size 0.55) (drill 0.2) (layers "F.Cu" "B.Cu") (free) (net 2))
  (via (at 139.9 73.025) (size 0.55) (drill 0.2) (layers "F.Cu" "B.Cu") (free) (net 2))
  (via (at 111.84 133.815) (size 0.55) (drill 0.2) (layers "F.Cu" "B.Cu") (free) (net 2))
  (via (at 120.621 106.658) (size 0.55) (drill 0.2) (layers "F.Cu" "B.Cu") (free) (net 2))
  (via (at 138.1 133.815) (size 0.55) (drill 0.2) (layers "F.Cu" "B.Cu") (free) (net 2))
  (via (at 117.46 117.215) (size 0.55) (drill 0.2) (layers "F.Cu" "B.Cu") (free) (net 2))
  (via (at 127.05 55.950001) (size 0.55) (drill 0.2) (layers "F.Cu" "B.Cu") (free) (net 2))
  (via (at 96.325 108.975) (size 0.55) (drill 0.2) (layers "F.Cu" "B.Cu") (free) (net 2))
  (via (at 140.2 144.49) (size 0.55) (drill 0.2) (layers "F.Cu" "B.Cu") (free) (net 2))
  (via (at 97.8 79) (size 0.55) (drill 0.2) (layers "F.Cu" "B.Cu") (free) (net 2))
  (via (at 121.05 55.95) (size 0.55) (drill 0.2) (layers "F.Cu" "B.Cu") (free) (net 2))
  (via (at 97.8 73.05) (size 0.55) (drill 0.2) (layers "F.Cu" "B.Cu") (free) (net 2))
  (via (at 143.2 53.05) (size 0.55) (drill 0.2) (layers "F.Cu" "B.Cu") (free) (net 2))
  (via (at 103.927065 121.887935) (size 0.55) (drill 0.2) (layers "F.Cu" "B.Cu") (free) (net 2))
  (via (at 94.8 130.565) (size 0.55) (drill 0.2) (layers "F.Cu" "B.Cu") (free) (net 2))
  (via (at 117.05 52.55) (size 0.55) (drill 0.2) (layers "F.Cu" "B.Cu") (free) (net 2))
  (via (at 100.96 123.515) (size 0.55) (drill 0.2) (layers "F.Cu" "B.Cu") (free) (net 2))
  (via (at 111.025 55.85) (size 0.55) (drill 0.2) (layers "F.Cu" "B.Cu") (free) (net 2))
  (via (at 143.2 79) (size 0.55) (drill 0.2) (layers "F.Cu" "B.Cu") (free) (net 2))
  (via (at 112.4075 138.415) (size 0.55) (drill 0.2) (layers "F.Cu" "B.Cu") (free) (net 2))
  (via (at 114.14 133.815) (size 0.55) (drill 0.2) (layers "F.Cu" "B.Cu") (free) (net 2))
  (via (at 98.1 98.975) (size 0.55) (drill 0.2) (layers "F.Cu" "B.Cu") (free) (net 2))
  (via (at 143.5 108.925) (size 0.55) (drill 0.2) (layers "F.Cu" "B.Cu") (free) (net 2))
  (via (at 140.2 88.9) (size 0.55) (drill 0.2) (layers "F.Cu" "B.Cu") (free) (net 2))
  (via (at 94.8 140.565) (size 0.55) (drill 0.2) (layers "F.Cu" "B.Cu") (free) (net 2))
  (via (at 122.14 120.115) (size 0.55) (drill 0.2) (layers "F.Cu" "B.Cu") (free) (net 2))
  (via (at 118.54 130.915) (size 0.55) (drill 0.2) (layers "F.Cu" "B.Cu") (free) (net 2))
  (via (at 143.5 103.025) (size 0.55) (drill 0.2) (layers "F.Cu" "B.Cu") (free) (net 2))
  (via (at 130.04 133.815) (size 0.55) (drill 0.2) (layers "F.Cu" "B.Cu") (free) (net 2))
  (via (at 125.88 146.335) (size 0.55) (drill 0.2) (layers "F.Cu" "B.Cu") (net 2))
  (via (at 127.74 133.815) (size 0.55) (drill 0.2) (layers "F.Cu" "B.Cu") (free) (net 2))
  (via (at 141.675 78.975) (size 0.55) (drill 0.2) (layers "F.Cu" "B.Cu") (free) (net 2))
  (via (at 111.24 130.915) (size 0.55) (drill 0.2) (layers "F.Cu" "B.Cu") (free) (net 2))
  (via (at 132.34 133.815) (size 0.55) (drill 0.2) (layers "F.Cu" "B.Cu") (free) (net 2))
  (via (at 110.56 117.215) (size 0.55) (drill 0.2) (layers "F.Cu" "B.Cu") (free) (net 2))
  (via (at 96.325 93.025) (size 0.55) (drill 0.2) (layers "F.Cu" "B.Cu") (free) (net 2))
  (via (at 136.65 54.96) (size 0.55) (drill 0.2) (layers "F.Cu" "B.Cu") (free) (net 2))
  (via (at 96.325 114.368973) (size 0.55) (drill 0.2) (layers "F.Cu" "B.Cu") (free) (net 2))
  (via (at 109.4 117.215) (size 0.55) (drill 0.2) (layers "F.Cu" "B.Cu") (free) (net 2))
  (via (at 94.8 124.615) (size 0.55) (drill 0.2) (layers "F.Cu" "B.Cu") (free) (net 2))
  (via (at 98.1 140.59) (size 0.55) (drill 0.2) (layers "F.Cu" "B.Cu") (free) (net 2))
  (via (at 128.76 117.215) (size 0.55) (drill 0.2) (layers "F.Cu" "B.Cu") (free) (net 2))
  (via (at 130.049 100.272) (size 0.55) (drill 0.2) (layers "F.Cu" "B.Cu") (free) (net 2))
  (via (at 141.725 108.925) (size 0.55) (drill 0.2) (layers "F.Cu" "B.Cu") (free) (net 2))
  (via (at 98.1 120.318973) (size 0.55) (drill 0.2) (layers "F.Cu" "B.Cu") (free) (net 2))
  (via (at 139.9 68.975) (size 0.55) (drill 0.2) (layers "F.Cu" "B.Cu") (free) (net 2))
  (via (at 141.675 68.975) (size 0.55) (drill 0.2) (layers "F.Cu" "B.Cu") (free) (net 2))
  (via (at 135.672935 123.487935) (size 0.55) (drill 0.2) (layers "F.Cu" "B.Cu") (free) (net 2))
  (via (at 134.852691 122.667691) (size 0.55) (drill 0.2) (layers "F.Cu" "B.Cu") (free) (net 2))
  (via (at 120.629 103.672) (size 0.55) (drill 0.2) (layers "F.Cu" "B.Cu") (free) (net 2))
  (via (at 126.645 130.915) (size 0.55) (drill 0.2) (layers "F.Cu" "B.Cu") (free) (net 2))
  (via (at 114.44 120.115) (size 0.55) (drill 0.2) (layers "F.Cu" "B.Cu") (free) (net 2))
  (via (at 94.8 98.95) (size 0.55) (drill 0.2) (layers "F.Cu" "B.Cu") (free) (net 2))
  (via (at 143.6 124.615) (size 0.55) (drill 0.2) (layers "F.Cu" "B.Cu") (free) (net 2))
  (via (at 96.325 88.975) (size 0.55) (drill 0.2) (layers "F.Cu" "B.Cu") (free) (net 2))
  (via (at 120.94 133.815) (size 0.55) (drill 0.2) (layers "F.Cu" "B.Cu") (free) (net 2))
  (via (at 120.8 117.215) (size 0.55) (drill 0.2) (layers "F.Cu" "B.Cu") (free) (net 2))
  (via (at 107.179756 118.635244) (size 0.55) (drill 0.2) (layers "F.Cu" "B.Cu") (free) (net 2))
  (via (at 143.200001 59) (size 0.55) (drill 0.2) (layers "F.Cu" "B.Cu") (free) (net 2))
  (via (at 124.399 103.622) (size 0.55) (drill 0.2) (layers "F.Cu" "B.Cu") (free) (net 2))
  (via (at 111.7 117.215) (size 0.55) (drill 0.2) (layers "F.Cu" "B.Cu") (free) (net 2))
  (via (at 141.8 150.615) (size 0.55) (drill 0.2) (layers "F.Cu" "B.Cu") (free) (net 2))
  (via (at 94.5 63.025) (size 0.55) (drill 0.2) (layers "F.Cu" "B.Cu") (free) (net 2))
  (segment (start 141.675 66.0075) (end 137 66.0075) (width 0.185) (layer "F.Cu") (net 3))
  (segment (start 137.000001 56.0075) (end 137 56) (width 0.185) (layer "F.Cu") (net 4))
  (segment (start 141.675 56.0075) (end 137.000001 56.0075) (width 0.185) (layer "F.Cu") (net 4))
  (via (at 137 56) (size 0.55) (drill 0.2) (layers "F.Cu" "B.Cu") (net 4))
  (segment (start 132.8 60.2) (end 120.9 60.2) (width 0.185) (layer "B.Cu") (net 4))
  (segment (start 119.7 61.4) (end 119.7 66.2) (width 0.185) (layer "B.Cu") (net 4))
  (segment (start 137 56) (end 132.8 60.2) (width 0.185) (layer "B.Cu") (net 4))
  (segment (start 120.9 60.2) (end 119.7 61.4) (width 0.185) (layer "B.Cu") (net 4))
  (segment (start 128.3 88.9925) (end 128.4 88.9925) (width 0.185) (layer "F.Cu") (net 5))
  (segment (start 141.71 85.9925) (end 141.725 86.0075) (width 0.185) (layer "F.Cu") (net 5))
  (segment (start 109.792501 86.007499) (end 109.792501 87.992499) (width 0.185) (layer "F.Cu") (net 5))
  (segment (start 96.325 85.9925) (end 141.71 85.9925) (width 0.185) (layer "F.Cu") (net 5))
  (segment (start 109.8 86) (end 109.792501 86.007499) (width 0.185) (layer "F.Cu") (net 5))
  (segment (start 110.7925 88.9925) (end 128.3 88.9925) (width 0.185) (layer "F.Cu") (net 5))
  (segment (start 109.792501 87.992499) (end 110.7925 88.9925) (width 0.185) (layer "F.Cu") (net 5))
  (segment (start 141.71 95.9925) (end 141.725 96.0075) (width 0.185) (layer "F.Cu") (net 6))
  (segment (start 111.015001 99.100002) (end 115.8 99.1) (width 0.185) (layer "F.Cu") (net 6))
  (segment (start 109.9 97.985) (end 111.015001 99.100002) (width 0.185) (layer "F.Cu") (net 6))
  (segment (start 109.9 96) (end 109.9 97.985) (width 0.185) (layer "F.Cu") (net 6))
  (segment (start 96.325 95.9925) (end 141.71 95.9925) (width 0.185) (layer "F.Cu") (net 6))
  (segment (start 136.183973 111.4725) (end 101.881028 111.4725) (width 0.185) (layer "F.Cu") (net 7))
  (segment (start 101.2925 110.883972) (end 101.2925 106.391764) (width 0.185) (layer "F.Cu") (net 7))
  (segment (start 100.893236 105.9925) (end 96.325 105.9925) (width 0.185) (layer "F.Cu") (net 7))
  (segment (start 136.7575 106.406765) (end 136.7575 110.898973) (width 0.185) (layer "F.Cu") (net 7))
  (segment (start 136.669632 111.111105) (end 136.396105 111.384632) (width 0.185) (layer "F.Cu") (net 7))
  (segment (start 101.668896 111.384632) (end 101.380368 111.096104) (width 0.185) (layer "F.Cu") (net 7))
  (segment (start 101.204632 106.179632) (end 101.105368 106.080368) (width 0.185) (layer "F.Cu") (net 7))
  (segment (start 136.944633 106.095368) (end 136.845368 106.194633) (width 0.185) (layer "F.Cu") (net 7))
  (segment (start 141.725 106.0075) (end 137.156765 106.0075) (width 0.185) (layer "F.Cu") (net 7))
  (arc (start 136.396105 111.384632) (mid 136.298778 111.449664) (end 136.183973 111.4725) (width 0.185) (layer "F.Cu") (net 7))
  (arc (start 136.845368 106.194633) (mid 136.780336 106.29196) (end 136.7575 106.406765) (width 0.185) (layer "F.Cu") (net 7))
  (arc (start 101.380368 111.096104) (mid 101.315336 110.998777) (end 101.2925 110.883972) (width 0.185) (layer "F.Cu") (net 7))
  (arc (start 101.2925 106.391764) (mid 101.269664 106.276959) (end 101.204632 106.179632) (width 0.185) (layer "F.Cu") (net 7))
  (arc (start 136.7575 110.898973) (mid 136.734664 111.013778) (end 136.669632 111.111105) (width 0.185) (layer "F.Cu") (net 7))
  (arc (start 101.105368 106.080368) (mid 101.008041 106.015336) (end 100.893236 105.9925) (width 0.185) (layer "F.Cu") (net 7))
  (arc (start 137.156765 106.0075) (mid 137.04196 106.030336) (end 136.944633 106.095368) (width 0.185) (layer "F.Cu") (net 7))
  (arc (start 101.881028 111.4725) (mid 101.766223 111.449664) (end 101.668896 111.384632) (width 0.185) (layer "F.Cu") (net 7))
  (segment (start 137.131764 117.299264) (end 141.7 117.299264) (width 0.185) (layer "F.Cu") (net 8))
  (segment (start 101.841027 111.8075) (end 136.143972 111.8075) (width 0.185) (layer "F.Cu") (net 8))
  (segment (start 136.356104 111.895368) (end 136.644632 112.183896) (width 0.185) (layer "F.Cu") (net 8))
  (segment (start 96.3 117.336473) (end 100.868235 117.336473) (width 0.185) (layer "F.Cu") (net 8))
  (segment (start 101.2675 116.937208) (end 101.2675 112.381027) (width 0.185) (layer "F.Cu") (net 8))
  (segment (start 136.7325 116.9) (end 136.7325 112.396028) (width 0.185) (layer "F.Cu") (net 8))
  (segment (start 101.080367 117.248605) (end 101.179632 117.14934) (width 0.185) (layer "F.Cu") (net 8))
  (segment (start 136.820368 117.112132) (end 136.919632 117.211396) (width 0.185) (layer "F.Cu") (net 8))
  (segment (start 101.355368 112.168895) (end 101.628895 111.895368) (width 0.185) (layer "F.Cu") (net 8))
  (arc (start 100.868235 117.336473) (mid 100.98304 117.313637) (end 101.080367 117.248605) (width 0.185) (layer "F.Cu") (net 8))
  (arc (start 136.7325 116.9) (mid 136.755336 117.014805) (end 136.820368 117.112132) (width 0.185) (layer "F.Cu") (net 8))
  (arc (start 136.143972 111.8075) (mid 136.258777 111.830336) (end 136.356104 111.895368) (width 0.185) (layer "F.Cu") (net 8))
  (arc (start 101.179632 117.14934) (mid 101.244664 117.052013) (end 101.2675 116.937208) (width 0.185) (layer "F.Cu") (net 8))
  (arc (start 136.644632 112.183896) (mid 136.709664 112.281223) (end 136.7325 112.396028) (width 0.185) (layer "F.Cu") (net 8))
  (arc (start 101.628895 111.895368) (mid 101.726222 111.830336) (end 101.841027 111.8075) (width 0.185) (layer "F.Cu") (net 8))
  (arc (start 101.2675 112.381027) (mid 101.290336 112.266222) (end 101.355368 112.168895) (width 0.185) (layer "F.Cu") (net 8))
  (arc (start 136.919632 117.211396) (mid 137.016959 117.276428) (end 137.131764 117.299264) (width 0.185) (layer "F.Cu") (net 8))
  (segment (start 96.325 137.6075) (end 112.3925 137.6075) (width 0.185) (layer "F.Cu") (net 9))
  (segment (start 126.6 137.615) (end 126.6075 137.6225) (width 0.185) (layer "F.Cu") (net 9))
  (segment (start 112.3925 137.6075) (end 112.4 137.615) (width 0.185) (layer "F.Cu") (net 9))
  (segment (start 126.6075 137.6225) (end 141.725 137.6225) (width 0.185) (layer "F.Cu") (net 9))
  (via (at 112.4 137.615) (size 0.55) (drill 0.2) (layers "F.Cu" "B.Cu") (net 9))
  (via (at 126.6 137.615) (size 0.55) (drill 0.2) (layers "F.Cu" "B.Cu") (net 9))
  (segment (start 112.4 137.615) (end 126.6 137.615) (width 0.185) (layer "B.Cu") (net 9))
  (segment (start 96.325 147.6075) (end 112.3925 147.6075) (width 0.185) (layer "F.Cu") (net 10))
  (segment (start 126.6075 147.6225) (end 141.725 147.6225) (width 0.185) (layer "F.Cu") (net 10))
  (via (at 126.6 147.615) (size 0.55) (drill 0.2) (layers "F.Cu" "B.Cu") (net 10))
  (via (at 112.4 147.615) (size 0.55) (drill 0.2) (layers "F.Cu" "B.Cu") (net 10))
  (segment (start 112.4 147.615) (end 126.6 147.615) (width 0.185) (layer "B.Cu") (net 10))
  (segment (start 100.95 55.992499) (end 96.275 55.992499) (width 0.185) (layer "F.Cu") (net 11))
  (segment (start 100.965 56.0075) (end 100.95 55.992499) (width 0.185) (layer "F.Cu") (net 11))
  (segment (start 114.0075 68.8325) (end 114.572862 68.8325) (width 0.185) (layer "F.Cu") (net 12))
  (segment (start 113.442138 68.8325) (end 114.0075 68.8325) (width 0.185) (layer "F.Cu") (net 12))
  (segment (start 114.0075 60.8325) (end 114.572862 60.8325) (width 0.185) (layer "F.Cu") (net 12))
  (segment (start 114.572862 63.2325) (end 114.0075 63.2325) (width 0.185) (layer "F.Cu") (net 12))
  (segment (start 114.572862 61.6325) (end 114.0075 61.6325) (width 0.185) (layer "F.Cu") (net 12))
  (segment (start 114.572862 69.6325) (end 114.4075 69.6325) (width 0.185) (layer "F.Cu") (net 12))
  (segment (start 114.0075 64.8325) (end 113.442138 64.8325) (width 0.185) (layer "F.Cu") (net 12))
  (segment (start 114.0075 66.4325) (end 113.442138 66.4325) (width 0.185) (layer "F.Cu") (net 12))
  (segment (start 114.0075 54.175) (end 114.0075 57.2325) (width 0.185) (layer "F.Cu") (net 12))
  (segment (start 114.0075 62.4325) (end 114.572862 62.4325) (width 0.185) (layer "F.Cu") (net 12))
  (segment (start 114.0075 60.0325) (end 113.442138 60.0325) (width 0.185) (layer "F.Cu") (net 12))
  (segment (start 114.572862 66.4325) (end 114.0075 66.4325) (width 0.185) (layer "F.Cu") (net 12))
  (segment (start 114.0075 67.2325) (end 114.572862 67.2325) (width 0.185) (layer "F.Cu") (net 12))
  (segment (start 114.0075 64.0325) (end 114.572862 64.0325) (width 0.185) (layer "F.Cu") (net 12))
  (segment (start 114.572862 64.8325) (end 114.0075 64.8325) (width 0.185) (layer "F.Cu") (net 12))
  (segment (start 113.442138 67.2325) (end 114.0075 67.2325) (width 0.185) (layer "F.Cu") (net 12))
  (segment (start 113.442138 62.4325) (end 114.0075 62.4325) (width 0.185) (layer "F.Cu") (net 12))
  (segment (start 113.442138 59.2325) (end 114.0075 59.2325) (width 0.185) (layer "F.Cu") (net 12))
  (segment (start 114.572862 58.4325) (end 114.4075 58.4325) (width 0.185) (layer "F.Cu") (net 12))
  (segment (start 114.4075 58.4325) (end 113.442138 58.4325) (width 0.185) (layer "F.Cu") (net 12))
  (segment (start 113.442138 65.6325) (end 114.0075 65.6325) (width 0.185) (layer "F.Cu") (net 12))
  (segment (start 114.0075 63.2325) (end 113.442138 63.2325) (width 0.185) (layer "F.Cu") (net 12))
  (segment (start 114.572862 60.0325) (end 114.0075 60.0325) (width 0.185) (layer "F.Cu") (net 12))
  (segment (start 114.4075 57.6325) (end 114.572862 57.6325) (width 0.185) (layer "F.Cu") (net 12))
  (segment (start 114.0075 65.6325) (end 114.572862 65.6325) (width 0.185) (layer "F.Cu") (net 12))
  (segment (start 114.0075 61.6325) (end 113.442138 61.6325) (width 0.185) (layer "F.Cu") (net 12))
  (segment (start 113.442138 64.0325) (end 114.0075 64.0325) (width 0.185) (layer "F.Cu") (net 12))
  (segment (start 114.0075 70.0325) (end 114.0075 70.707989) (width 0.185) (layer "F.Cu") (net 12))
  (segment (start 113.442138 60.8325) (end 114.0075 60.8325) (width 0.185) (layer "F.Cu") (net 12))
  (segment (start 114.0075 59.2325) (end 114.572862 59.2325) (width 0.185) (layer "F.Cu") (net 12))
  (segment (start 114.0075 68.0325) (end 113.442138 68.0325) (width 0.185) (layer "F.Cu") (net 12))
  (segment (start 114.572862 68.0325) (end 114.0075 68.0325) (width 0.185) (layer "F.Cu") (net 12))
  (arc (start 114.572862 68.8325) (mid 114.855705 68.949657) (end 114.972862 69.2325) (width 0.185) (layer "F.Cu") (net 12))
  (arc (start 114.972862 59.6325) (mid 114.855705 59.915343) (end 114.572862 60.0325) (width 0.185) (layer "F.Cu") (net 12))
  (arc (start 114.972862 67.6325) (mid 114.855705 67.915343) (end 114.572862 68.0325) (width 0.185) (layer "F.Cu") (net 12))
  (arc (start 114.572862 59.2325) (mid 114.855705 59.349657) (end 114.972862 59.6325) (width 0.185) (layer "F.Cu") (net 12))
  (arc (start 114.0075 57.2325) (mid 114.124657 57.515343) (end 114.4075 57.6325) (width 0.185) (layer "F.Cu") (net 12))
  (arc (start 114.572862 64.0325) (mid 114.855705 64.149657) (end 114.972862 64.4325) (width 0.185) (layer "F.Cu") (net 12))
  (arc (start 113.042138 68.4325) (mid 113.159295 68.715343) (end 113.442138 68.8325) (width 0.185) (layer "F.Cu") (net 12))
  (arc (start 114.972862 66.0325) (mid 114.855705 66.315343) (end 114.572862 66.4325) (width 0.185) (layer "F.Cu") (net 12))
  (arc (start 114.972862 58.0325) (mid 114.855705 58.315343) (end 114.572862 58.4325) (width 0.185) (layer "F.Cu") (net 12))
  (arc (start 114.572862 62.4325) (mid 114.855705 62.549657) (end 114.972862 62.8325) (width 0.185) (layer "F.Cu") (net 12))
  (arc (start 114.572862 60.8325) (mid 114.855705 60.949657) (end 114.972862 61.2325) (width 0.185) (layer "F.Cu") (net 12))
  (arc (start 113.042138 58.8325) (mid 113.159295 59.115343) (end 113.442138 59.2325) (width 0.185) (layer "F.Cu") (net 12))
  (arc (start 113.442138 68.0325) (mid 113.159295 68.149657) (end 113.042138 68.4325) (width 0.185) (layer "F.Cu") (net 12))
  (arc (start 113.442138 58.4325) (mid 113.159295 58.549657) (end 113.042138 58.8325) (width 0.185) (layer "F.Cu") (net 12))
  (arc (start 114.972862 69.2325) (mid 114.855705 69.515343) (end 114.572862 69.6325) (width 0.185) (layer "F.Cu") (net 12))
  (arc (start 114.4075 69.6325) (mid 114.124657 69.749657) (end 114.0075 70.0325) (width 0.185) (layer "F.Cu") (net 12))
  (arc (start 113.042138 65.2325) (mid 113.159295 65.515343) (end 113.442138 65.6325) (width 0.185) (layer "F.Cu") (net 12))
  (arc (start 113.042138 63.6325) (mid 113.159295 63.915343) (end 113.442138 64.0325) (width 0.185) (layer "F.Cu") (net 12))
  (arc (start 114.972862 62.8325) (mid 114.855705 63.115343) (end 114.572862 63.2325) (width 0.185) (layer "F.Cu") (net 12))
  (arc (start 113.442138 63.2325) (mid 113.159295 63.349657) (end 113.042138 63.6325) (width 0.185) (layer "F.Cu") (net 12))
  (arc (start 114.572862 57.6325) (mid 114.855705 57.749657) (end 114.972862 58.0325) (width 0.185) (layer "F.Cu") (net 12))
  (arc (start 113.442138 60.0325) (mid 113.159295 60.149657) (end 113.042138 60.4325) (width 0.185) (layer "F.Cu") (net 12))
  (arc (start 113.442138 64.8325) (mid 113.159295 64.949657) (end 113.042138 65.2325) (width 0.185) (layer "F.Cu") (net 12))
  (arc (start 113.442138 66.4325) (mid 113.159295 66.549657) (end 113.042138 66.8325) (width 0.185) (layer "F.Cu") (net 12))
  (arc (start 114.972862 61.2325) (mid 114.855705 61.515343) (end 114.572862 61.6325) (width 0.185) (layer "F.Cu") (net 12))
  (arc (start 114.972862 64.4325) (mid 114.855705 64.715343) (end 114.572862 64.8325) (width 0.185) (layer "F.Cu") (net 12))
  (arc (start 113.042138 60.4325) (mid 113.159295 60.715343) (end 113.442138 60.8325) (width 0.185) (layer "F.Cu") (net 12))
  (arc (start 113.042138 66.8325) (mid 113.159295 67.115343) (end 113.442138 67.2325) (width 0.185) (layer "F.Cu") (net 12))
  (arc (start 114.572862 67.2325) (mid 114.855705 67.349657) (end 114.972862 67.6325) (width 0.185) (layer "F.Cu") (net 12))
  (arc (start 113.442138 61.6325) (mid 113.159295 61.749657) (end 113.042138 62.0325) (width 0.185) (layer "F.Cu") (net 12))
  (arc (start 113.042138 62.0325) (mid 113.159295 62.315343) (end 113.442138 62.4325) (width 0.185) (layer "F.Cu") (net 12))
  (arc (start 114.572862 65.6325) (mid 114.855705 65.749657) (end 114.972862 66.0325) (width 0.185) (layer "F.Cu") (net 12))
  (segment (start 124.87002 62.425) (end 124.0575 62.425) (width 0.185) (layer "F.Cu") (net 13))
  (segment (start 124.87002 59.745) (end 124.225 59.745) (width 0.185) (layer "F.Cu") (net 13))
  (segment (start 124.0575 61.755) (end 123.24498 61.755) (width 0.185) (layer "F.Cu") (net 13))
  (segment (start 124.87002 63.765) (end 124.225 63.765) (width 0.185) (layer "F.Cu") (net 13))
  (segment (start 124.87002 63.095) (end 124.0575 63.095) (width 0.185) (layer "F.Cu") (net 13))
  (segment (start 124.0575 62.09) (end 124.87002 62.09) (width 0.185) (layer "F.Cu") (net 13))
  (segment (start 124.225 59.745) (end 123.24498 59.745) (width 0.185) (layer "F.Cu") (net 13))
  (segment (start 123.24498 60.08) (end 124.0575 60.08) (width 0.185) (layer "F.Cu") (net 13))
  (segment (start 123.24498 63.43) (end 124.0575 63.43) (width 0.185) (layer "F.Cu") (net 13))
  (segment (start 124.0575 60.08) (end 124.87002 60.08) (width 0.185) (layer "F.Cu") (net 13))
  (segment (start 124.225 59.41) (end 124.87002 59.41) (width 0.185) (layer "F.Cu") (net 13))
  (segment (start 124.0575 60.415) (end 123.24498 60.415) (width 0.185) (layer "F.Cu") (net 13))
  (segment (start 124.0575 63.9325) (end 124.0575 69.13168) (width 0.185) (layer "F.Cu") (net 13))
  (segment (start 124.0575 61.085) (end 123.24498 61.085) (width 0.185) (layer "F.Cu") (net 13))
  (segment (start 124.0575 54.225) (end 124.0575 59.2425) (width 0.185) (layer "F.Cu") (net 13))
  (segment (start 124.0575 60.75) (end 124.87002 60.75) (width 0.185) (layer "F.Cu") (net 13))
  (segment (start 124.87002 61.755) (end 124.0575 61.755) (width 0.185) (layer "F.Cu") (net 13))
  (segment (start 124.0575 62.425) (end 123.24498 62.425) (width 0.185) (layer "F.Cu") (net 13))
  (segment (start 123.24498 62.76) (end 124.0575 62.76) (width 0.185) (layer "F.Cu") (net 13))
  (segment (start 124.0575 63.43) (end 124.87002 63.43) (width 0.185) (layer "F.Cu") (net 13))
  (segment (start 123.24498 62.09) (end 124.0575 62.09) (width 0.185) (layer "F.Cu") (net 13))
  (segment (start 124.0575 61.42) (end 124.87002 61.42) (width 0.185) (layer "F.Cu") (net 13))
  (segment (start 123.24498 60.75) (end 124.0575 60.75) (width 0.185) (layer "F.Cu") (net 13))
  (segment (start 124.0575 69.13168) (end 124.0575 70.7575) (width 0.185) (layer "F.Cu") (net 13))
  (segment (start 124.87002 60.415) (end 124.0575 60.415) (width 0.185) (layer "F.Cu") (net 13))
  (segment (start 124.0575 63.095) (end 123.24498 63.095) (width 0.185) (layer "F.Cu") (net 13))
  (segment (start 124.0575 62.76) (end 124.87002 62.76) (width 0.185) (layer "F.Cu") (net 13))
  (segment (start 123.24498 61.42) (end 124.0575 61.42) (width 0.185) (layer "F.Cu") (net 13))
  (segment (start 124.87002 61.085) (end 124.0575 61.085) (width 0.185) (layer "F.Cu") (net 13))
  (arc (start 123.07748 59.9125) (mid 123.12654 60.03094) (end 123.24498 60.08) (width 0.185) (layer "F.Cu") (net 13))
  (arc (start 124.87002 60.75) (mid 124.98846 60.79906) (end 125.03752 60.9175) (width 0.185) (layer "F.Cu") (net 13))
  (arc (start 123.07748 63.2625) (mid 123.12654 63.38094) (end 123.24498 63.43) (width 0.185) (layer "F.Cu") (net 13))
  (arc (start 125.03752 62.9275) (mid 124.98846 63.04594) (end 124.87002 63.095) (width 0.185) (layer "F.Cu") (net 13))
  (arc (start 123.24498 61.755) (mid 123.12654 61.80406) (end 123.07748 61.9225) (width 0.185) (layer "F.Cu") (net 13))
  (arc (start 125.03752 61.5875) (mid 124.98846 61.70594) (end 124.87002 61.755) (width 0.185) (layer "F.Cu") (net 13))
  (arc (start 124.87002 61.42) (mid 124.98846 61.46906) (end 125.03752 61.5875) (width 0.185) (layer "F.Cu") (net 13))
  (arc (start 123.07748 61.9225) (mid 123.12654 62.04094) (end 123.24498 62.09) (width 0.185) (layer "F.Cu") (net 13))
  (arc (start 123.07748 62.5925) (mid 123.12654 62.71094) (end 123.24498 62.76) (width 0.185) (layer "F.Cu") (net 13))
  (arc (start 123.24498 61.085) (mid 123.12654 61.13406) (end 123.07748 61.2525) (width 0.185) (layer "F.Cu") (net 13))
  (arc (start 124.87002 60.08) (mid 124.98846 60.12906) (end 125.03752 60.2475) (width 0.185) (layer "F.Cu") (net 13))
  (arc (start 123.24498 60.415) (mid 123.12654 60.46406) (end 123.07748 60.5825) (width 0.185) (layer "F.Cu") (net 13))
  (arc (start 123.07748 61.2525) (mid 123.12654 61.37094) (end 123.24498 61.42) (width 0.185) (layer "F.Cu") (net 13))
  (arc (start 123.07748 60.5825) (mid 123.12654 60.70094) (end 123.24498 60.75) (width 0.185) (layer "F.Cu") (net 13))
  (arc (start 124.225 63.765) (mid 124.10656 63.81406) (end 124.0575 63.9325) (width 0.185) (layer "F.Cu") (net 13))
  (arc (start 123.24498 62.425) (mid 123.12654 62.47406) (end 123.07748 62.5925) (width 0.185) (layer "F.Cu") (net 13))
  (arc (start 124.87002 62.76) (mid 124.98846 62.80906) (end 125.03752 62.9275) (width 0.185) (layer "F.Cu") (net 13))
  (arc (start 125.03752 63.5975) (mid 124.98846 63.71594) (end 124.87002 63.765) (width 0.185) (layer "F.Cu") (net 13))
  (arc (start 123.24498 59.745) (mid 123.12654 59.79406) (end 123.07748 59.9125) (width 0.185) (layer "F.Cu") (net 13))
  (arc (start 125.03752 60.9175) (mid 124.98846 61.03594) (end 124.87002 61.085) (width 0.185) (layer "F.Cu") (net 13))
  (arc (start 124.0575 59.2425) (mid 124.10656 59.36094) (end 124.225 59.41) (width 0.185) (layer "F.Cu") (net 13))
  (arc (start 125.03752 62.2575) (mid 124.98846 62.37594) (end 124.87002 62.425) (width 0.185) (layer "F.Cu") (net 13))
  (arc (start 124.87002 62.09) (mid 124.98846 62.13906) (end 125.03752 62.2575) (width 0.185) (layer "F.Cu") (net 13))
  (arc (start 125.03752 59.5775) (mid 124.98846 59.69594) (end 124.87002 59.745) (width 0.185) (layer "F.Cu") (net 13))
  (arc (start 123.24498 63.095) (mid 123.12654 63.14406) (end 123.07748 63.2625) (width 0.185) (layer "F.Cu") (net 13))
  (arc (start 124.87002 59.41) (mid 124.98846 59.45906) (end 125.03752 59.5775) (width 0.185) (layer "F.Cu") (net 13))
  (arc (start 125.03752 60.2475) (mid 124.98846 60.36594) (end 124.87002 60.415) (width 0.185) (layer "F.Cu") (net 13))
  (arc (start 124.87002 63.43) (mid 124.98846 63.47906) (end 125.03752 63.5975) (width 0.185) (layer "F.Cu") (net 13))

  (zone (net 0) (net_name "") (layers "F.Cu" "In1.Cu") (hatch edge 0.508)
    (connect_pads (clearance 0))
    (min_thickness 0.254)
    (keepout (tracks allowed) (vias allowed) (pads allowed ) (copperpour not_allowed) (footprints allowed))
    (fill (thermal_gap 0.508) (thermal_bridge_width 0.508))
    (polygon
      (pts
        (xy 139.4795 104.75)
        (xy 144 104.75)
        (xy 144 107.24)
        (xy 139.4795 107.240001)
      )
    )
  )
  (zone (net 1) (net_name "Net-(J1-Pad1)") (layer "F.Cu") (hatch edge 0.508)
    (priority 17540)
    (connect_pads yes (clearance 0))
    (min_thickness 0.0254) (filled_areas_thickness no)
    (fill yes (thermal_gap 0.508) (thermal_bridge_width 0.508))
    (polygon
      (pts
        (xy 140.508625 75.9925)
        (xy 140.48059 76.085)
        (xy 140.601673 76.11412)
        (xy 140.659688 76.19316)
        (xy 140.669419 76.309641)
        (xy 140.645647 76.45108)
        (xy 140.603153 76.604999)
        (xy 140.556721 76.75892)
        (xy 140.521134 76.90036)
        (xy 140.51117 77.01684)
        (xy 140.541615 77.09588)
        (xy 140.62725 77.125)
        (xy 141.675 77.125)
        (xy 141.81239 75.97851)
        (xy 141.662584 74.835068)
        (xy 140.614832 74.835068)
        (xy 140.527761 74.865947)
        (xy 140.497839 74.947498)
        (xy 140.509773 75.067019)
        (xy 140.54827 75.21181)
        (xy 140.598035 75.369171)
        (xy 140.643774 75.526402)
        (xy 140.670193 75.6708)
        (xy 140.661998 75.789667)
        (xy 140.603895 75.8703)
        (xy 140.48059 75.9)
      )
    )
  )
  (zone (net 2) (net_name "GND") (layer "F.Cu") (hatch edge 0.508)
    (connect_pads (clearance 0.508))
    (min_thickness 0.0254) (filled_areas_thickness no)
    (fill yes (thermal_gap 0.508) (thermal_bridge_width 0.508))
    (polygon
      (pts
        (xy 123.25 130.915)
        (xy 121.66 130.915)
        (xy 121.66 120.085)
        (xy 123.25 120.085)
      )
    )
  )
  (zone (net 2) (net_name "GND") (layer "F.Cu") (hatch edge 0.508)
    (connect_pads yes (clearance 0.508))
    (min_thickness 0.0254) (filled_areas_thickness no)
    (fill yes (thermal_gap 0.508) (thermal_bridge_width 0.508))
    (polygon
      (pts
        (xy 140.715 126.525)
        (xy 140.714999 128.715)
        (xy 126.710001 128.715002)
        (xy 126.71 126.525002)
      )
    )
  )
  (zone (net 0) (net_name "") (layers "F.Cu" "In1.Cu") (hatch edge 0.508)
    (connect_pads (clearance 0))
    (min_thickness 0.254)
    (keepout (tracks allowed) (vias allowed) (pads allowed ) (copperpour not_allowed) (footprints allowed))
    (fill (thermal_gap 0.508) (thermal_bridge_width 0.508))
    (polygon
      (pts
        (xy 93.9795 94.75)
        (xy 98.5 94.75)
        (xy 98.5 97.24)
        (xy 93.9795 97.240001)
      )
    )
  )
  (zone (net 0) (net_name "") (layers "F.Cu" "In1.Cu") (hatch edge 0.508)
    (connect_pads (clearance 0))
    (min_thickness 0.254)
    (keepout (tracks allowed) (vias allowed) (pads allowed ) (copperpour not_allowed) (footprints allowed))
    (fill (thermal_gap 0.508) (thermal_bridge_width 0.508))
    (polygon
      (pts
        (xy 139.4795 146.365)
        (xy 144 146.365)
        (xy 144 148.855)
        (xy 139.4795 148.855001)
      )
    )
  )
  (zone (net 2) (net_name "GND") (layer "F.Cu") (hatch edge 0.508)
    (connect_pads (clearance 0.508))
    (min_thickness 0.0254) (filled_areas_thickness no)
    (fill yes (thermal_gap 0.508) (thermal_bridge_width 0.508))
    (polygon
      (pts
        (xy 111.64 130.915)
        (xy 109.45 130.915)
        (xy 109.45 119.36)
        (xy 111.64 119.36)
      )
    )
  )
  (zone (net 0) (net_name "") (layers "F.Cu" "In1.Cu") (hatch edge 0.508)
    (connect_pads (clearance 0))
    (min_thickness 0.254)
    (keepout (tracks allowed) (vias allowed) (pads allowed ) (copperpour not_allowed) (footprints allowed))
    (fill (thermal_gap 0.508) (thermal_bridge_width 0.508))
    (polygon
      (pts
        (xy 93.9295 64.75)
        (xy 98.45 64.75)
        (xy 98.45 67.24)
        (xy 93.9295 67.240001)
      )
    )
  )
  (zone (net 0) (net_name "") (layers "F.Cu" "In1.Cu") (hatch edge 0.508)
    (connect_pads (clearance 0))
    (min_thickness 0.254)
    (keepout (tracks allowed) (vias allowed) (pads allowed ) (copperpour not_allowed) (footprints allowed))
    (fill (thermal_gap 0.508) (thermal_bridge_width 0.508))
    (polygon
      (pts
        (xy 94.0295 146.365)
        (xy 98.55 146.365)
        (xy 98.55 148.855)
        (xy 94.0295 148.855001)
      )
    )
  )
  (zone (net 0) (net_name "") (layers "F.Cu" "In1.Cu") (hatch edge 0.508)
    (connect_pads (clearance 0))
    (min_thickness 0.254)
    (keepout (tracks allowed) (vias allowed) (pads allowed ) (copperpour not_allowed) (footprints allowed))
    (fill (thermal_gap 0.508) (thermal_bridge_width 0.508))
    (polygon
      (pts
        (xy 93.9545 74.735)
        (xy 98.475 74.735)
        (xy 98.475 77.225)
        (xy 93.9545 77.225001)
      )
    )
  )
  (zone (net 2) (net_name "GND") (layer "F.Cu") (hatch edge 0.508)
    (connect_pads (clearance 0.508))
    (min_thickness 0.0254) (filled_areas_thickness no)
    (fill yes (thermal_gap 0.508) (thermal_bridge_width 0.508))
    (polygon
      (pts
        (xy 114.84 130.915)
        (xy 113.25 130.915)
        (xy 113.25 120.085)
        (xy 114.84 120.085)
      )
    )
  )
  (zone (net 0) (net_name "") (layers "F.Cu" "In1.Cu") (hatch edge 0.508)
    (connect_pads (clearance 0))
    (min_thickness 0.254)
    (keepout (tracks allowed) (vias allowed) (pads allowed ) (copperpour not_allowed) (footprints allowed))
    (fill (thermal_gap 0.508) (thermal_bridge_width 0.508))
    (polygon
      (pts
        (xy 139.4795 54.75)
        (xy 144 54.75)
        (xy 144 57.24)
        (xy 139.4795 57.240001)
      )
    )
  )
  (zone (net 0) (net_name "") (layers "F.Cu" "In1.Cu") (hatch edge 0.508)
    (connect_pads (clearance 0))
    (min_thickness 0.254)
    (keepout (tracks allowed) (vias allowed) (pads allowed ) (copperpour not_allowed) (footprints allowed))
    (fill (thermal_gap 0.508) (thermal_bridge_width 0.508))
    (polygon
      (pts
        (xy 112.717499 56.2705)
        (xy 112.717499 51.85)
        (xy 115.207499 51.85)
        (xy 115.2075 56.2705)
      )
    )
  )
  (zone (net 2) (net_name "GND") (layer "F.Cu") (hatch edge 0.508)
    (connect_pads yes (clearance 0.508))
    (min_thickness 0.0254) (filled_areas_thickness no)
    (fill yes (thermal_gap 0.508) (thermal_bridge_width 0.508))
    (polygon
      (pts
        (xy 109.865 126.51)
        (xy 109.864999 128.7)
        (xy 98.310001 128.7)
        (xy 98.31 126.51)
      )
    )
  )
  (zone (net 2) (net_name "GND") (layer "F.Cu") (hatch edge 0.508)
    (connect_pads (clearance 0.508))
    (min_thickness 0.0254) (filled_areas_thickness no)
    (fill yes (thermal_gap 0.508) (thermal_bridge_width 0.508))
    (polygon
      (pts
        (xy 127.04 130.92)
        (xy 124.85 130.92)
        (xy 124.85 119.365)
        (xy 127.04 119.365)
      )
    )
  )
  (zone (net 0) (net_name "") (layers "F.Cu" "In1.Cu") (hatch edge 0.508)
    (connect_pads (clearance 0))
    (min_thickness 0.254)
    (keepout (tracks allowed) (vias allowed) (pads allowed ) (copperpour not_allowed) (footprints allowed))
    (fill (thermal_gap 0.508) (thermal_bridge_width 0.508))
    (polygon
      (pts
        (xy 122.809999 56.3705)
        (xy 122.809999 51.95)
        (xy 125.299999 51.95)
        (xy 125.3 56.3705)
      )
    )
  )
  (zone (net 0) (net_name "") (layers "F.Cu" "In1.Cu") (hatch edge 0.508)
    (connect_pads (clearance 0))
    (min_thickness 0.254)
    (keepout (tracks allowed) (vias allowed) (pads allowed ) (copperpour not_allowed) (footprints allowed))
    (fill (thermal_gap 0.508) (thermal_bridge_width 0.508))
    (polygon
      (pts
        (xy 93.9795 136.365)
        (xy 98.5 136.365)
        (xy 98.5 138.855)
        (xy 93.9795 138.855001)
      )
    )
  )
  (zone (net 0) (net_name "") (layers "F.Cu" "In1.Cu") (hatch edge 0.508)
    (connect_pads (clearance 0))
    (min_thickness 0.254)
    (keepout (tracks allowed) (vias allowed) (pads allowed ) (copperpour not_allowed) (footprints allowed))
    (fill (thermal_gap 0.508) (thermal_bridge_width 0.508))
    (polygon
      (pts
        (xy 93.9795 84.75)
        (xy 98.5 84.75)
        (xy 98.5 87.24)
        (xy 93.9795 87.240001)
      )
    )
  )
  (zone (net 0) (net_name "") (layers "F.Cu" "In1.Cu") (hatch edge 0.508)
    (connect_pads (clearance 0))
    (min_thickness 0.254)
    (keepout (tracks allowed) (vias allowed) (pads allowed ) (copperpour not_allowed) (footprints allowed))
    (fill (thermal_gap 0.508) (thermal_bridge_width 0.508))
    (polygon
      (pts
        (xy 139.4295 64.75)
        (xy 143.95 64.75)
        (xy 143.95 67.24)
        (xy 139.4295 67.240001)
      )
    )
  )
  (zone (net 0) (net_name "") (layers "F.Cu" "In1.Cu") (hatch edge 0.508)
    (connect_pads (clearance 0))
    (min_thickness 0.254)
    (keepout (tracks allowed) (vias allowed) (pads allowed ) (copperpour not_allowed) (footprints allowed))
    (fill (thermal_gap 0.508) (thermal_bridge_width 0.508))
    (polygon
      (pts
        (xy 139.4795 74.735)
        (xy 144 74.735)
        (xy 144 77.225)
        (xy 139.4795 77.225)
      )
    )
  )
  (zone (net 0) (net_name "") (layers "F.Cu" "In1.Cu") (hatch edge 0.508)
    (connect_pads (clearance 0))
    (min_thickness 0.254)
    (keepout (tracks allowed) (vias allowed) (pads allowed ) (copperpour not_allowed) (footprints allowed))
    (fill (thermal_gap 0.508) (thermal_bridge_width 0.508))
    (polygon
      (pts
        (xy 139.5295 84.75)
        (xy 144.05 84.75)
        (xy 144.05 87.24)
        (xy 139.5295 87.240001)
      )
    )
  )
  (zone (net 0) (net_name "") (layers "F.Cu" "In1.Cu") (hatch edge 0.508)
    (connect_pads (clearance 0))
    (min_thickness 0.254)
    (keepout (tracks allowed) (vias allowed) (pads allowed ) (copperpour not_allowed) (footprints allowed))
    (fill (thermal_gap 0.508) (thermal_bridge_width 0.508))
    (polygon
      (pts
        (xy 93.9795 116.093973)
        (xy 98.5 116.093973)
        (xy 98.5 118.583973)
        (xy 93.9795 118.583974)
      )
    )
  )
  (zone (net 0) (net_name "") (layers "F.Cu" "In1.Cu") (hatch edge 0.508)
    (connect_pads (clearance 0))
    (min_thickness 0.254)
    (keepout (tracks allowed) (vias allowed) (pads allowed ) (copperpour not_allowed) (footprints allowed))
    (fill (thermal_gap 0.508) (thermal_bridge_width 0.508))
    (polygon
      (pts
        (xy 93.9295 54.75)
        (xy 98.45 54.75)
        (xy 98.45 57.24)
        (xy 93.9295 57.240001)
      )
    )
  )
  (zone (net 0) (net_name "") (layers "F.Cu" "In1.Cu") (hatch edge 0.508)
    (connect_pads (clearance 0))
    (min_thickness 0.254)
    (keepout (tracks allowed) (vias allowed) (pads allowed ) (copperpour not_allowed) (footprints allowed))
    (fill (thermal_gap 0.508) (thermal_bridge_width 0.508))
    (polygon
      (pts
        (xy 93.9795 104.75)
        (xy 98.5 104.75)
        (xy 98.5 107.24)
        (xy 93.9795 107.240001)
      )
    )
  )
  (zone (net 2) (net_name "GND") (layer "F.Cu") (hatch edge 0.508)
    (connect_pads (clearance 0.508))
    (min_thickness 0.0254) (filled_areas_thickness no)
    (fill yes (thermal_gap 0.508) (thermal_bridge_width 0.508))
    (polygon
      (pts
        (xy 119.045 130.915)
        (xy 117.455 130.915)
        (xy 117.455 120.085)
        (xy 119.045 120.085)
      )
    )
  )
  (zone (net 1) (net_name "Net-(J1-Pad1)") (layer "F.Cu") (hatch edge 0.508)
    (priority 17540)
    (connect_pads yes (clearance 0))
    (min_thickness 0.0254) (filled_areas_thickness no)
    (fill yes (thermal_gap 0.508) (thermal_bridge_width 0.508))
    (polygon
      (pts
        (xy 140.508625 75.9925)
        (xy 140.48059 76.085)
        (xy 140.601673 76.11412)
        (xy 140.659688 76.19316)
        (xy 140.669419 76.309641)
        (xy 140.645647 76.45108)
        (xy 140.603153 76.604999)
        (xy 140.556721 76.75892)
        (xy 140.521134 76.90036)
        (xy 140.51117 77.01684)
        (xy 140.541615 77.09588)
        (xy 140.62725 77.125)
        (xy 141.675 77.125)
        (xy 141.81239 75.97851)
        (xy 141.662584 74.835068)
        (xy 140.614832 74.835068)
        (xy 140.527761 74.865947)
        (xy 140.497839 74.947498)
        (xy 140.509773 75.067019)
        (xy 140.54827 75.21181)
        (xy 140.598035 75.369171)
        (xy 140.643774 75.526402)
        (xy 140.670193 75.6708)
        (xy 140.661998 75.789667)
        (xy 140.603895 75.8703)
        (xy 140.48059 75.9)
      )
    )
  )
  (zone (net 0) (net_name "") (layers "F.Cu" "In1.Cu") (hatch edge 0.508)
    (connect_pads (clearance 0))
    (min_thickness 0.254)
    (keepout (tracks allowed) (vias allowed) (pads allowed ) (copperpour not_allowed) (footprints allowed))
    (fill (thermal_gap 0.508) (thermal_bridge_width 0.508))
    (polygon
      (pts
        (xy 139.5295 94.75)
        (xy 144.05 94.75)
        (xy 144.05 97.24)
        (xy 139.5295 97.240001)
      )
    )
  )
  (zone (net 2) (net_name "GND") (layer "F.Cu") (hatch edge 0.508)
    (connect_pads yes (clearance 0.508))
    (min_thickness 0.2) (filled_areas_thickness no)
    (fill yes (thermal_gap 0.508) (thermal_bridge_width 0.508))
    (polygon
      (pts
        (xy 132.809 107.127)
        (xy 120.239 107.127)
        (xy 120.239 99.852)
        (xy 132.809 99.852)
      )
    )
  )
  (zone (net 0) (net_name "") (layers "F.Cu" "In1.Cu") (hatch edge 0.508)
    (connect_pads (clearance 0))
    (min_thickness 0.254)
    (keepout (tracks allowed) (vias allowed) (pads allowed ) (copperpour not_allowed) (footprints allowed))
    (fill (thermal_gap 0.508) (thermal_bridge_width 0.508))
    (polygon
      (pts
        (xy 139.5295 136.365)
        (xy 144.05 136.365)
        (xy 144.05 138.855)
        (xy 139.5295 138.855001)
      )
    )
  )
  (zone (net 0) (net_name "") (layers "F.Cu" "In1.Cu") (hatch edge 0.508)
    (connect_pads (clearance 0))
    (min_thickness 0.254)
    (keepout (tracks allowed) (vias allowed) (pads allowed ) (copperpour not_allowed) (footprints allowed))
    (fill (thermal_gap 0.508) (thermal_bridge_width 0.508))
    (polygon
      (pts
        (xy 139.4795 116.1)
        (xy 144 116.1)
        (xy 144 118.59)
        (xy 139.4795 118.590001)
      )
    )
  )
  (zone (net 0) (net_name "") (layer "In1.Cu") (hatch edge 0.508)
    (connect_pads yes (clearance 0))
    (min_thickness 0)
    (keepout (tracks allowed) (vias allowed) (pads allowed ) (copperpour not_allowed) (footprints allowed))
    (fill (thermal_gap 0.508) (thermal_bridge_width 0.508))
    (polygon
      (pts
        (xy 126.350141 146.333475)
        (xy 126.331181 146.201083)
        (xy 126.275825 146.079334)
        (xy 126.188523 145.978015)
        (xy 126.076293 145.905271)
        (xy 125.948158 145.86695)
        (xy 125.814417 145.866133)
        (xy 125.685823 145.902886)
        (xy 125.572713 145.974253)
        (xy 125.48418 146.074498)
        (xy 125.42734 146.195562)
        (xy 125.406764 146.327712)
        (xy 125.424105 146.460326)
        (xy 125.47797 146.582743)
        (xy 125.564028 146.685121)
        (xy 125.67536 146.75923)
        (xy 125.803018 146.799113)
        (xy 125.936739 146.801564)
        (xy 126.065772 146.766385)
        (xy 126.179746 146.696405)
        (xy 126.269497 146.59725)
        (xy 126.327811 146.476889)
        (xy 126.35 146.345)
      )
    )
  )
  (zone (net 0) (net_name "") (layer "In1.Cu") (hatch edge 0.508)
    (connect_pads yes (clearance 0))
    (min_thickness 0)
    (keepout (tracks allowed) (vias allowed) (pads allowed ) (copperpour not_allowed) (footprints allowed))
    (fill (thermal_gap 0.508) (thermal_bridge_width 0.508))
    (polygon
      (pts
        (xy 113.66896 146.417392)
        (xy 113.65 146.285)
        (xy 113.594644 146.163251)
        (xy 113.507342 146.061932)
        (xy 113.395112 145.989188)
        (xy 113.266977 145.950867)
        (xy 113.133236 145.95005)
        (xy 113.004642 145.986803)
        (xy 112.891532 146.05817)
        (xy 112.802999 146.158415)
        (xy 112.746159 146.279479)
        (xy 112.725583 146.411629)
        (xy 112.742924 146.544243)
        (xy 112.796789 146.66666)
        (xy 112.882847 146.769038)
        (xy 112.994179 146.843147)
        (xy 113.121837 146.88303)
        (xy 113.255558 146.885481)
        (xy 113.384591 146.850302)
        (xy 113.498565 146.780322)
        (xy 113.588316 146.681167)
        (xy 113.64663 146.560806)
        (xy 113.668819 146.428917)
      )
    )
  )
  (zone (net 2) (net_name "GND") (layers "In1.Cu" "In2.Cu") (hatch edge 0.508)
    (connect_pads yes (clearance 0.508))
    (min_thickness 0.15) (filled_areas_thickness no)
    (fill yes (thermal_gap 0.508) (thermal_bridge_width 0.508))
    (polygon
      (pts
        (xy 144 152)
        (xy 94 152)
        (xy 94 52)
        (xy 144 52)
      )
    )
  )
  (zone (net 0) (net_name "") (layer "In1.Cu") (hatch edge 0.508)
    (connect_pads yes (clearance 0))
    (min_thickness 0.254)
    (keepout (tracks allowed) (vias allowed) (pads allowed ) (copperpour not_allowed) (footprints allowed))
    (fill (thermal_gap 0.508) (thermal_bridge_width 0.508))
    (polygon
      (pts
        (xy 135.3 124.015)
        (xy 138.3 124.015)
        (xy 139.3 125.015)
        (xy 139.3 125.315)
        (xy 139.6 125.615)
        (xy 144 125.615)
        (xy 144 129.715)
        (xy 139.8 129.715)
        (xy 139.3 130.215)
        (xy 139.3 133.415)
        (xy 98.8 133.415)
        (xy 98.8 130.015)
        (xy 98.5 129.715)
        (xy 94.1 129.715)
        (xy 94.1 125.515)
        (xy 98.5 125.515)
        (xy 98.9 125.115)
        (xy 98.9 124.115)
        (xy 102.6 124.115)
        (xy 108.9 117.815)
        (xy 129.1 117.815)
      )
    )
  )
  (zone (net 0) (net_name "") (layer "In2.Cu") (hatch edge 0.508)
    (connect_pads yes (clearance 0))
    (min_thickness 0)
    (keepout (tracks allowed) (vias allowed) (pads allowed ) (copperpour not_allowed) (footprints allowed))
    (fill (thermal_gap 0.508) (thermal_bridge_width 0.508))
    (polygon
      (pts
        (xy 111.981706 146.405)
        (xy 111.962746 146.272608)
        (xy 111.90739 146.150859)
        (xy 111.820088 146.04954)
        (xy 111.707858 145.976796)
        (xy 111.579723 145.938475)
        (xy 111.445982 145.937658)
        (xy 111.317388 145.974411)
        (xy 111.204278 146.045778)
        (xy 111.115745 146.146023)
        (xy 111.058905 146.267087)
        (xy 111.038329 146.399237)
        (xy 111.05567 146.531851)
        (xy 111.109535 146.654268)
        (xy 111.195593 146.756646)
        (xy 111.306925 146.830755)
        (xy 111.434583 146.870638)
        (xy 111.568304 146.873089)
        (xy 111.697337 146.83791)
        (xy 111.811311 146.76793)
        (xy 111.901062 146.668775)
        (xy 111.959376 146.548414)
        (xy 111.981565 146.416525)
      )
    )
  )
  (zone (net 0) (net_name "") (layer "In2.Cu") (hatch edge 0.508)
    (connect_pads yes (clearance 0))
    (min_thickness 0)
    (keepout (tracks allowed) (vias allowed) (pads allowed ) (copperpour not_allowed) (footprints allowed))
    (fill (thermal_gap 0.508) (thermal_bridge_width 0.508))
    (polygon
      (pts
        (xy 127.84896 146.347392)
        (xy 127.83 146.215)
        (xy 127.774644 146.093251)
        (xy 127.687342 145.991932)
        (xy 127.575112 145.919188)
        (xy 127.446977 145.880867)
        (xy 127.313236 145.88005)
        (xy 127.184642 145.916803)
        (xy 127.071532 145.98817)
        (xy 126.982999 146.088415)
        (xy 126.926159 146.209479)
        (xy 126.905583 146.341629)
        (xy 126.922924 146.474243)
        (xy 126.976789 146.59666)
        (xy 127.062847 146.699038)
        (xy 127.174179 146.773147)
        (xy 127.301837 146.81303)
        (xy 127.435558 146.815481)
        (xy 127.564591 146.780302)
        (xy 127.678565 146.710322)
        (xy 127.768316 146.611167)
        (xy 127.82663 146.490806)
        (xy 127.848819 146.358917)
      )
    )
  )
  (zone (net 4) (net_name "Net-(AE1-Pad1)") (layer "B.Cu") (hatch edge 0.508)
    (connect_pads yes (clearance 0.508))
    (min_thickness 0.0254) (filled_areas_thickness no)
    (fill yes (thermal_gap 0.508) (thermal_bridge_width 0.508))
    (polygon
      (pts
        (xy 131.315 84.5)
        (xy 108.085 84.5)
        (xy 108.085 66.2)
        (xy 131.315 66.2)
      )
    )
  )
  (zone (net 0) (net_name "") (layer "B.Mask") (hatch edge 0.508)
    (connect_pads yes (clearance 0.508))
    (min_thickness 0) (filled_areas_thickness no)
    (fill yes (thermal_gap 0.508) (thermal_bridge_width 0.508))
    (polygon
      (pts
        (xy 113.19 136.915)
        (xy 113.24 136.965)
        (xy 111.64 136.965)
        (xy 112.19 136.415)
        (xy 112.69 136.415)
      )
    )
  )
  (zone (net 0) (net_name "") (layer "B.Mask") (hatch edge 0.508)
    (connect_pads yes (clearance 0.508))
    (min_thickness 0) (filled_areas_thickness no)
    (fill yes (thermal_gap 0.508) (thermal_bridge_width 0.508))
    (polygon
      (pts
        (xy 125.81 138.295)
        (xy 125.76 138.245)
        (xy 127.36 138.245)
        (xy 126.809999 138.795)
        (xy 126.31 138.795)
      )
    )
  )
  (zone (net 0) (net_name "") (layer "B.Mask") (hatch edge 0.508)
    (connect_pads yes (clearance 0.508))
    (min_thickness 0) (filled_areas_thickness no)
    (fill yes (thermal_gap 0.508) (thermal_bridge_width 0.508))
    (polygon
      (pts
        (xy 127.3 136.915)
        (xy 127.35 136.965)
        (xy 125.75 136.965)
        (xy 126.3 136.415)
        (xy 126.8 136.415)
      )
    )
  )
  (zone (net 0) (net_name "") (layer "B.Mask") (hatch edge 0.508)
    (connect_pads yes (clearance 0.508))
    (min_thickness 0) (filled_areas_thickness no)
    (fill yes (thermal_gap 0.508) (thermal_bridge_width 0.508))
    (polygon
      (pts
        (xy 111.7 138.295)
        (xy 111.65 138.245)
        (xy 113.25 138.245)
        (xy 112.699999 138.795)
        (xy 112.2 138.795)
      )
    )
  )
  (zone (net 0) (net_name "") (layer "F.Mask") (hatch edge 0.508)
    (connect_pads yes (clearance 0.508))
    (min_thickness 0) (filled_areas_thickness no)
    (fill yes (thermal_gap 0.508) (thermal_bridge_width 0.508))
    (polygon
      (pts
        (xy 101.43 105.36)
        (xy 101.91 105.84)
        (xy 101.91 106.739999)
        (xy 100.63 106.74)
        (xy 100.54 106.65)
        (xy 100.54 105.36)
      )
    )
  )
  (zone (net 0) (net_name "") (layer "F.Mask") (hatch edge 0.508)
    (connect_pads yes (clearance 0.508))
    (min_thickness 0) (filled_areas_thickness no)
    (fill yes (thermal_gap 0.508) (thermal_bridge_width 0.508))
    (polygon
      (pts
        (xy 136.212 112.583501)
        (xy 135.732 112.1035)
        (xy 135.732 111.2035)
        (xy 137.012 111.2035)
        (xy 137.102 111.2935)
        (xy 137.102 112.583501)
      )
    )
  )
  (zone (net 0) (net_name "") (layer "F.Mask") (hatch edge 0.508)
    (connect_pads yes (clearance 0.508))
    (min_thickness 0) (filled_areas_thickness no)
    (fill yes (thermal_gap 0.508) (thermal_bridge_width 0.508))
    (polygon
      (pts
        (xy 136.14 105.85)
        (xy 136.62 105.37)
        (xy 137.52 105.37)
        (xy 137.52 106.65)
        (xy 137.43 106.74)
        (xy 136.14 106.74)
      )
    )
  )
  (zone (net 0) (net_name "") (layer "F.Mask") (hatch edge 0.508)
    (connect_pads yes (clearance 0.508))
    (min_thickness 0.254) (filled_areas_thickness no)
    (fill yes (thermal_gap 0.508) (thermal_bridge_width 0.508))
    (polygon
      (pts
        (xy 125.2 58.9)
        (xy 125.9 59.6)
        (xy 125.9 63.6)
        (xy 125.2 64.3)
        (xy 125.2 71.2)
        (xy 123 71.2)
        (xy 123 64.2875)
        (xy 122.3125 63.6)
        (xy 122.3125 59.5)
        (xy 122.9125 58.9)
        (xy 122.9125 56.3205)
        (xy 125.2 56.3205)
      )
    )
  )
  (zone (net 0) (net_name "") (layer "F.Mask") (hatch edge 0.508)
    (connect_pads yes (clearance 0.508))
    (min_thickness 0) (filled_areas_thickness no)
    (fill yes (thermal_gap 0.508) (thermal_bridge_width 0.508))
    (polygon
      (pts
        (xy 101.91 117.493973)
        (xy 101.43 117.973973)
        (xy 100.53 117.973973)
        (xy 100.53 116.693973)
        (xy 100.62 116.603973)
        (xy 101.91 116.603973)
      )
    )
  )
  (zone (net 0) (net_name "") (layer "F.Mask") (hatch edge 0.508)
    (connect_pads yes (clearance 0.508))
    (min_thickness 0) (filled_areas_thickness no)
    (fill yes (thermal_gap 0.508) (thermal_bridge_width 0.508))
    (polygon
      (pts
        (xy 125.883 136.926)
        (xy 125.833 136.976)
        (xy 127.433 136.976)
        (xy 126.883 136.426)
        (xy 126.383 136.426)
      )
    )
  )
  (zone (net 0) (net_name "") (layer "F.Mask") (hatch edge 0.508)
    (connect_pads yes (clearance 0.508))
    (min_thickness 0.254) (filled_areas_thickness no)
    (fill yes (thermal_gap 0.508) (thermal_bridge_width 0.508))
    (polygon
      (pts
        (xy 115.2 56.7)
        (xy 115.9 57.4)
        (xy 115.9 70.4)
        (xy 115.2 71.1)
        (xy 115.2 71.0795)
        (xy 113 71.0795)
        (xy 113 71.1)
        (xy 112.3 70.5)
        (xy 112.3125 57.3)
        (xy 112.9125 56.7)
        (xy 112.9125 56.2)
        (xy 115.2 56.2)
      )
    )
  )
  (zone (net 0) (net_name "") (layer "F.Mask") (hatch edge 0.508)
    (connect_pads yes (clearance 0.508))
    (min_thickness 0) (filled_areas_thickness no)
    (fill yes (thermal_gap 0.508) (thermal_bridge_width 0.508))
    (polygon
      (pts
        (xy 136.62 117.931764)
        (xy 136.14 117.451764)
        (xy 136.140001 116.551765)
        (xy 137.42 116.551764)
        (xy 137.51 116.641764)
        (xy 137.51 117.931764)
      )
    )
  )
  (zone (net 0) (net_name "") (layer "F.Mask") (hatch edge 0.508)
    (connect_pads yes (clearance 0.508))
    (min_thickness 0) (filled_areas_thickness no)
    (fill yes (thermal_gap 0.508) (thermal_bridge_width 0.508))
    (polygon
      (pts
        (xy 127.373 138.306)
        (xy 127.423 138.256)
        (xy 125.823 138.256)
        (xy 126.373001 138.806)
        (xy 126.873 138.806)
      )
    )
  )
  (zone (net 0) (net_name "") (layer "F.Mask") (hatch edge 0.508)
    (connect_pads yes (clearance 0.508))
    (min_thickness 0) (filled_areas_thickness no)
    (fill yes (thermal_gap 0.508) (thermal_bridge_width 0.508))
    (polygon
      (pts
        (xy 113.12 138.312)
        (xy 113.17 138.262)
        (xy 111.57 138.262)
        (xy 112.120001 138.812)
        (xy 112.62 138.812)
      )
    )
  )
  (zone (net 0) (net_name "") (layer "F.Mask") (hatch edge 0.508)
    (connect_pads yes (clearance 0.508))
    (min_thickness 0.254) (filled_areas_thickness no)
    (fill yes (thermal_gap 0.508) (thermal_bridge_width 0.508))
    (polygon
      (pts
        (xy 135.3 124.165)
        (xy 138.3 124.165)
        (xy 139.25 125.115)
        (xy 139.25 133.365)
        (xy 99 133.365)
        (xy 99 124.215)
        (xy 102.75 124.215)
        (xy 109.05 117.915)
        (xy 129.05 117.915)
      )
    )
  )
  (zone (net 0) (net_name "") (layer "F.Mask") (hatch edge 0.508)
    (connect_pads yes (clearance 0.508))
    (min_thickness 0) (filled_areas_thickness no)
    (fill yes (thermal_gap 0.508) (thermal_bridge_width 0.508))
    (polygon
      (pts
        (xy 110.569875 97.729875)
        (xy 111.300125 98.460125)
        (xy 111.299875 98.460125)
        (xy 111.299875 99.760125)
        (xy 110.569875 99.760125)
        (xy 109.269875 98.460125)
        (xy 109.269875 96.470125)
        (xy 110.569875 96.470125)
      )
    )
  )
  (zone (net 0) (net_name "") (layer "F.Mask") (hatch edge 0.508)
    (connect_pads yes (clearance 0.508))
    (min_thickness 0) (filled_areas_thickness no)
    (fill yes (thermal_gap 0.508) (thermal_bridge_width 0.508))
    (polygon
      (pts
        (xy 111.63 136.932)
        (xy 111.58 136.982)
        (xy 113.18 136.982)
        (xy 112.63 136.432)
        (xy 112.13 136.432)
      )
    )
  )
  (zone (net 0) (net_name "") (layer "F.Mask") (hatch edge 0.508)
    (connect_pads yes (clearance 0.508))
    (min_thickness 0) (filled_areas_thickness no)
    (fill yes (thermal_gap 0.508) (thermal_bridge_width 0.508))
    (polygon
      (pts
        (xy 101.8035 110.703999)
        (xy 102.2835 111.184)
        (xy 102.2835 112.084)
        (xy 101.0035 112.084)
        (xy 100.9135 111.994)
        (xy 100.9135 110.703999)
      )
    )
  )
  (zone (net 0) (net_name "") (layer "F.Mask") (hatch edge 0.508)
    (connect_pads yes (clearance 0.508))
    (min_thickness 0) (filled_areas_thickness no)
    (fill yes (thermal_gap 0.508) (thermal_bridge_width 0.508))
    (polygon
      (pts
        (xy 102.278 112.177)
        (xy 101.798 112.657)
        (xy 100.898 112.657)
        (xy 100.898 111.376999)
        (xy 100.988 111.287)
        (xy 102.278 111.287)
      )
    )
  )
  (zone (net 0) (net_name "") (layer "F.Mask") (hatch edge 0.508)
    (connect_pads yes (clearance 0.508))
    (min_thickness 0) (filled_areas_thickness no)
    (fill yes (thermal_gap 0.508) (thermal_bridge_width 0.508))
    (polygon
      (pts
        (xy 135.7375 111.1105)
        (xy 136.2175 110.6305)
        (xy 137.1175 110.6305)
        (xy 137.1175 111.9105)
        (xy 137.0275 112.0005)
        (xy 135.7375 112.0005)
      )
    )
  )
  (zone (net 0) (net_name "") (layer "F.Mask") (hatch edge 0.508)
    (connect_pads yes (clearance 0.508))
    (min_thickness 0) (filled_areas_thickness no)
    (fill yes (thermal_gap 0.508) (thermal_bridge_width 0.508))
    (polygon
      (pts
        (xy 110.48 87.59975)
        (xy 111.21025 88.33)
        (xy 111.21 88.33)
        (xy 111.21 89.63)
        (xy 110.48 89.63)
        (xy 109.18 88.33)
        (xy 109.18 86.34)
        (xy 110.48 86.34)
      )
    )
  )
)
